FILE_TYPE = MACRO_DRAWING;
SET COLOR_WIRE YELLOW;
SET COLOR_PROP ORANGE;
SET COLOR_DOT WHITE;
SET COLOR_ARC YELLOW;
SET COLOR_BODY GREEN;
SET COLOR_NOTE PURPLE;
SET PROP_DISPLAY VALUE;
SET PAGE_NUMBER P12;
FORCEADD GENOA_SP5..3
(-4775 3575);
FORCEPROP 1 LAST LOCATION U25
J 0
(-5420 6406);
DISPLAY 0.489362 (-5420 6406);
PAINT SKYBLUE (-5420 6406);
FORCEPROP 0 LAST $SEC 3
J 0
(-5400 6550);
DISPLAY 0.680851 (-5400 6550);
PAINT MONO (-5400 6550);
DISPLAY INVISIBLE (-5400 6550);
FORCEPROP 0 LAST CDS_SEC 3
J 0
(-5400 6550);
DISPLAY 1.021277 (-5400 6550);
DISPLAY INVISIBLE (-5400 6550);
FORCEPROP 0 LASTPIN (-5575 2950) $PN BC57
J 2
(-5585 2960);
DISPLAY 0.489362 (-5585 2960);
PAINT MONO (-5585 2960);
FORCEPROP 0 LASTPIN (-5575 2900) $PN BD56
J 2
(-5585 2910);
DISPLAY 0.489362 (-5585 2910);
PAINT MONO (-5585 2910);
FORCEPROP 0 LASTPIN (-5575 1800) $PN BF56
J 2
(-5585 1810);
DISPLAY 0.489362 (-5585 1810);
PAINT MONO (-5585 1810);
FORCEPROP 0 LASTPIN (-5575 1750) $PN BG57
J 2
(-5585 1760);
DISPLAY 0.489362 (-5585 1760);
PAINT MONO (-5585 1760);
FORCEPROP 0 LASTPIN (-5575 2100) $PN AT55
J 2
(-5585 2110);
DISPLAY 0.489362 (-5585 2110);
PAINT MONO (-5585 2110);
FORCEPROP 0 LASTPIN (-5575 2000) $PN AU55
J 2
(-5585 2010);
DISPLAY 0.489362 (-5585 2010);
PAINT MONO (-5585 2010);
FORCEPROP 0 LASTPIN (-5575 2800) $PN AV56
J 2
(-5585 2810);
DISPLAY 0.489362 (-5585 2810);
PAINT MONO (-5585 2810);
FORCEPROP 0 LASTPIN (-5575 2750) $PN AW55
J 2
(-5585 2760);
DISPLAY 0.489362 (-5585 2760);
PAINT MONO (-5585 2760);
FORCEPROP 0 LASTPIN (-5575 2650) $PN BN55
J 2
(-5585 2660);
DISPLAY 0.489362 (-5585 2660);
PAINT MONO (-5585 2660);
FORCEPROP 0 LASTPIN (-5575 1650) $PN AU57
J 2
(-5585 1660);
DISPLAY 0.489362 (-5585 1660);
PAINT MONO (-5585 1660);
FORCEPROP 0 LASTPIN (-5575 1600) $PN AV55
J 2
(-5585 1610);
DISPLAY 0.489362 (-5585 1610);
PAINT MONO (-5585 1610);
FORCEPROP 0 LASTPIN (-5575 1500) $PN BP55
J 2
(-5585 1510);
DISPLAY 0.489362 (-5585 1510);
PAINT MONO (-5585 1510);
FORCEPROP 0 LASTPIN (-5575 3800) $PN AW57
J 2
(-5585 3810);
DISPLAY 0.489362 (-5585 3810);
PAINT MONO (-5585 3810);
FORCEPROP 0 LASTPIN (-5575 3750) $PN AY56
J 2
(-5585 3760);
DISPLAY 0.489362 (-5585 3760);
PAINT MONO (-5585 3760);
FORCEPROP 0 LASTPIN (-5575 3700) $PN AY55
J 2
(-5585 3710);
DISPLAY 0.489362 (-5585 3710);
PAINT MONO (-5585 3710);
FORCEPROP 0 LASTPIN (-5575 3650) $PN BA55
J 2
(-5585 3660);
DISPLAY 0.489362 (-5585 3660);
PAINT MONO (-5585 3660);
FORCEPROP 0 LASTPIN (-5575 3600) $PN BA57
J 2
(-5585 3610);
DISPLAY 0.489362 (-5585 3610);
PAINT MONO (-5585 3610);
FORCEPROP 0 LASTPIN (-5575 3550) $PN BB56
J 2
(-5585 3560);
DISPLAY 0.489362 (-5585 3560);
PAINT MONO (-5585 3560);
FORCEPROP 0 LASTPIN (-5575 3500) $PN BB55
J 2
(-5585 3510);
DISPLAY 0.489362 (-5585 3510);
PAINT MONO (-5585 3510);
FORCEPROP 0 LASTPIN (-3975 2350) $PN AJ57
J 0
(-3965 2360);
DISPLAY 0.489362 (-3965 2360);
PAINT MONO (-3965 2360);
FORCEPROP 0 LASTPIN (-3975 2300) $PN AK55
J 0
(-3965 2310);
DISPLAY 0.489362 (-3965 2310);
PAINT MONO (-3965 2310);
FORCEPROP 0 LASTPIN (-3975 2250) $PN AK56
J 0
(-3965 2260);
DISPLAY 0.489362 (-3965 2260);
PAINT MONO (-3965 2260);
FORCEPROP 0 LASTPIN (-3975 2200) $PN AL55
J 0
(-3965 2210);
DISPLAY 0.489362 (-3965 2210);
PAINT MONO (-3965 2210);
FORCEPROP 0 LASTPIN (-3975 2150) $PN AN57
J 0
(-3965 2160);
DISPLAY 0.489362 (-3965 2160);
PAINT MONO (-3965 2160);
FORCEPROP 0 LASTPIN (-3975 2100) $PN AP55
J 0
(-3965 2110);
DISPLAY 0.489362 (-3965 2110);
PAINT MONO (-3965 2110);
FORCEPROP 0 LASTPIN (-3975 2050) $PN AP56
J 0
(-3965 2060);
DISPLAY 0.489362 (-3965 2060);
PAINT MONO (-3965 2060);
FORCEPROP 0 LASTPIN (-3975 2000) $PN AR55
J 0
(-3965 2010);
DISPLAY 0.489362 (-3965 2010);
PAINT MONO (-3965 2010);
FORCEPROP 0 LASTPIN (-3975 5950) $PN E57
J 0
(-3965 5960);
DISPLAY 0.489362 (-3965 5960);
PAINT MONO (-3965 5960);
FORCEPROP 0 LASTPIN (-3975 5900) $PN F55
J 0
(-3965 5910);
DISPLAY 0.489362 (-3965 5910);
PAINT MONO (-3965 5910);
FORCEPROP 0 LASTPIN (-3975 5850) $PN F56
J 0
(-3965 5860);
DISPLAY 0.489362 (-3965 5860);
PAINT MONO (-3965 5860);
FORCEPROP 0 LASTPIN (-3975 5800) $PN G55
J 0
(-3965 5810);
DISPLAY 0.489362 (-3965 5810);
PAINT MONO (-3965 5810);
FORCEPROP 0 LASTPIN (-3975 5750) $PN J57
J 0
(-3965 5760);
DISPLAY 0.489362 (-3965 5760);
PAINT MONO (-3965 5760);
FORCEPROP 0 LASTPIN (-3975 5700) $PN K55
J 0
(-3965 5710);
DISPLAY 0.489362 (-3965 5710);
PAINT MONO (-3965 5710);
FORCEPROP 0 LASTPIN (-3975 5650) $PN K56
J 0
(-3965 5660);
DISPLAY 0.489362 (-3965 5660);
PAINT MONO (-3965 5660);
FORCEPROP 0 LASTPIN (-3975 5600) $PN L55
J 0
(-3965 5610);
DISPLAY 0.489362 (-3965 5610);
PAINT MONO (-3965 5610);
FORCEPROP 0 LASTPIN (-3975 5500) $PN L57
J 0
(-3965 5510);
DISPLAY 0.489362 (-3965 5510);
PAINT MONO (-3965 5510);
FORCEPROP 0 LASTPIN (-3975 5450) $PN M55
J 0
(-3965 5460);
DISPLAY 0.489362 (-3965 5460);
PAINT MONO (-3965 5460);
FORCEPROP 0 LASTPIN (-3975 5400) $PN M56
J 0
(-3965 5410);
DISPLAY 0.489362 (-3965 5410);
PAINT MONO (-3965 5410);
FORCEPROP 0 LASTPIN (-3975 5350) $PN N55
J 0
(-3965 5360);
DISPLAY 0.489362 (-3965 5360);
PAINT MONO (-3965 5360);
FORCEPROP 0 LASTPIN (-3975 5300) $PN R57
J 0
(-3965 5310);
DISPLAY 0.489362 (-3965 5310);
PAINT MONO (-3965 5310);
FORCEPROP 0 LASTPIN (-3975 5250) $PN T55
J 0
(-3965 5260);
DISPLAY 0.489362 (-3965 5260);
PAINT MONO (-3965 5260);
FORCEPROP 0 LASTPIN (-3975 5200) $PN T56
J 0
(-3965 5210);
DISPLAY 0.489362 (-3965 5210);
PAINT MONO (-3965 5210);
FORCEPROP 0 LASTPIN (-3975 5150) $PN U55
J 0
(-3965 5160);
DISPLAY 0.489362 (-3965 5160);
PAINT MONO (-3965 5160);
FORCEPROP 0 LASTPIN (-3975 5050) $PN U57
J 0
(-3965 5060);
DISPLAY 0.489362 (-3965 5060);
PAINT MONO (-3965 5060);
FORCEPROP 0 LASTPIN (-3975 5000) $PN V55
J 0
(-3965 5010);
DISPLAY 0.489362 (-3965 5010);
PAINT MONO (-3965 5010);
FORCEPROP 0 LASTPIN (-3975 4950) $PN V56
J 0
(-3965 4960);
DISPLAY 0.489362 (-3965 4960);
PAINT MONO (-3965 4960);
FORCEPROP 0 LASTPIN (-3975 4900) $PN W55
J 0
(-3965 4910);
DISPLAY 0.489362 (-3965 4910);
PAINT MONO (-3965 4910);
FORCEPROP 0 LASTPIN (-3975 4850) $PN AA57
J 0
(-3965 4860);
DISPLAY 0.489362 (-3965 4860);
PAINT MONO (-3965 4860);
FORCEPROP 0 LASTPIN (-3975 4800) $PN AB55
J 0
(-3965 4810);
DISPLAY 0.489362 (-3965 4810);
PAINT MONO (-3965 4810);
FORCEPROP 0 LASTPIN (-3975 4750) $PN AB56
J 0
(-3965 4760);
DISPLAY 0.489362 (-3965 4760);
PAINT MONO (-3965 4760);
FORCEPROP 0 LASTPIN (-3975 4700) $PN AC55
J 0
(-3965 4710);
DISPLAY 0.489362 (-3965 4710);
PAINT MONO (-3965 4710);
FORCEPROP 0 LASTPIN (-3975 4600) $PN AC57
J 0
(-3965 4610);
DISPLAY 0.489362 (-3965 4610);
PAINT MONO (-3965 4610);
FORCEPROP 0 LASTPIN (-3975 4550) $PN AD55
J 0
(-3965 4560);
DISPLAY 0.489362 (-3965 4560);
PAINT MONO (-3965 4560);
FORCEPROP 0 LASTPIN (-3975 4500) $PN AD56
J 0
(-3965 4510);
DISPLAY 0.489362 (-3965 4510);
PAINT MONO (-3965 4510);
FORCEPROP 0 LASTPIN (-3975 4450) $PN AE55
J 0
(-3965 4460);
DISPLAY 0.489362 (-3965 4460);
PAINT MONO (-3965 4460);
FORCEPROP 0 LASTPIN (-3975 4400) $PN AG57
J 0
(-3965 4410);
DISPLAY 0.489362 (-3965 4410);
PAINT MONO (-3965 4410);
FORCEPROP 0 LASTPIN (-3975 4350) $PN AH55
J 0
(-3965 4360);
DISPLAY 0.489362 (-3965 4360);
PAINT MONO (-3965 4360);
FORCEPROP 0 LASTPIN (-3975 4300) $PN AH56
J 0
(-3965 4310);
DISPLAY 0.489362 (-3965 4310);
PAINT MONO (-3965 4310);
FORCEPROP 0 LASTPIN (-3975 4250) $PN AJ55
J 0
(-3965 4260);
DISPLAY 0.489362 (-3965 4260);
PAINT MONO (-3965 4260);
FORCEPROP 0 LASTPIN (-5575 5950) $PN G57
J 2
(-5585 5960);
DISPLAY 0.489362 (-5585 5960);
PAINT MONO (-5585 5960);
FORCEPROP 0 LASTPIN (-5575 5850) $PN N57
J 2
(-5585 5860);
DISPLAY 0.489362 (-5585 5860);
PAINT MONO (-5585 5860);
FORCEPROP 0 LASTPIN (-5575 5750) $PN W57
J 2
(-5585 5760);
DISPLAY 0.489362 (-5585 5760);
PAINT MONO (-5585 5760);
FORCEPROP 0 LASTPIN (-5575 5650) $PN AE57
J 2
(-5585 5660);
DISPLAY 0.489362 (-5585 5660);
PAINT MONO (-5585 5660);
FORCEPROP 0 LASTPIN (-5575 5550) $PN AL57
J 2
(-5585 5560);
DISPLAY 0.489362 (-5585 5560);
PAINT MONO (-5585 5560);
FORCEPROP 0 LASTPIN (-5575 5450) $PN J55
J 2
(-5585 5460);
DISPLAY 0.489362 (-5585 5460);
PAINT MONO (-5585 5460);
FORCEPROP 0 LASTPIN (-5575 5350) $PN R55
J 2
(-5585 5360);
DISPLAY 0.489362 (-5585 5360);
PAINT MONO (-5585 5360);
FORCEPROP 0 LASTPIN (-5575 5250) $PN AA55
J 2
(-5585 5260);
DISPLAY 0.489362 (-5585 5260);
PAINT MONO (-5585 5260);
FORCEPROP 0 LASTPIN (-5575 5150) $PN AG55
J 2
(-5585 5160);
DISPLAY 0.489362 (-5585 5160);
PAINT MONO (-5585 5160);
FORCEPROP 0 LASTPIN (-5575 5050) $PN AN55
J 2
(-5585 5060);
DISPLAY 0.489362 (-5585 5060);
PAINT MONO (-5585 5060);
FORCEPROP 0 LASTPIN (-5575 5900) $PN H56
J 2
(-5585 5910);
DISPLAY 0.489362 (-5585 5910);
PAINT MONO (-5585 5910);
FORCEPROP 0 LASTPIN (-5575 5800) $PN P56
J 2
(-5585 5810);
DISPLAY 0.489362 (-5585 5810);
PAINT MONO (-5585 5810);
FORCEPROP 0 LASTPIN (-5575 5700) $PN Y56
J 2
(-5585 5710);
DISPLAY 0.489362 (-5585 5710);
PAINT MONO (-5585 5710);
FORCEPROP 0 LASTPIN (-5575 5600) $PN AF56
J 2
(-5585 5610);
DISPLAY 0.489362 (-5585 5610);
PAINT MONO (-5585 5610);
FORCEPROP 0 LASTPIN (-5575 5500) $PN AM56
J 2
(-5585 5510);
DISPLAY 0.489362 (-5585 5510);
PAINT MONO (-5585 5510);
FORCEPROP 0 LASTPIN (-5575 5400) $PN H55
J 2
(-5585 5410);
DISPLAY 0.489362 (-5585 5410);
PAINT MONO (-5585 5410);
FORCEPROP 0 LASTPIN (-5575 5300) $PN P55
J 2
(-5585 5310);
DISPLAY 0.489362 (-5585 5310);
PAINT MONO (-5585 5310);
FORCEPROP 0 LASTPIN (-5575 5200) $PN Y55
J 2
(-5585 5210);
DISPLAY 0.489362 (-5585 5210);
PAINT MONO (-5585 5210);
FORCEPROP 0 LASTPIN (-5575 5100) $PN AF55
J 2
(-5585 5110);
DISPLAY 0.489362 (-5585 5110);
PAINT MONO (-5585 5110);
FORCEPROP 0 LASTPIN (-5575 5000) $PN AM55
J 2
(-5585 5010);
DISPLAY 0.489362 (-5585 5010);
PAINT MONO (-5585 5010);
FORCEPROP 0 LASTPIN (-5575 2550) $PN BC55
J 2
(-5585 2560);
DISPLAY 0.489362 (-5585 2560);
PAINT MONO (-5585 2560);
FORCEPROP 0 LASTPIN (-5575 2450) $PN BM55
J 2
(-5585 2460);
DISPLAY 0.489362 (-5585 2460);
PAINT MONO (-5585 2460);
FORCEPROP 0 LASTPIN (-5575 2400) $PN BN57
J 2
(-5585 2410);
DISPLAY 0.489362 (-5585 2410);
PAINT MONO (-5585 2410);
FORCEPROP 0 LASTPIN (-5575 2300) $PN BP56
J 2
(-5585 2310);
DISPLAY 0.489362 (-5585 2310);
PAINT MONO (-5585 2310);
FORCEPROP 0 LASTPIN (-5575 1400) $PN BL55
J 2
(-5585 1410);
DISPLAY 0.489362 (-5585 1410);
PAINT MONO (-5585 1410);
FORCEPROP 0 LASTPIN (-5575 1350) $PN BM56
J 2
(-5585 1360);
DISPLAY 0.489362 (-5585 1360);
PAINT MONO (-5585 1360);
FORCEPROP 0 LASTPIN (-5575 1250) $PN BR57
J 2
(-5585 1260);
DISPLAY 0.489362 (-5585 1260);
PAINT MONO (-5585 1260);
FORCEPROP 0 LASTPIN (-5575 3400) $PN BG55
J 2
(-5585 3410);
DISPLAY 0.489362 (-5585 3410);
PAINT MONO (-5585 3410);
FORCEPROP 0 LASTPIN (-5575 3350) $PN BH55
J 2
(-5585 3360);
DISPLAY 0.489362 (-5585 3360);
PAINT MONO (-5585 3360);
FORCEPROP 0 LASTPIN (-5575 3300) $PN BH56
J 2
(-5585 3310);
DISPLAY 0.489362 (-5585 3310);
PAINT MONO (-5585 3310);
FORCEPROP 0 LASTPIN (-5575 3250) $PN BJ57
J 2
(-5585 3260);
DISPLAY 0.489362 (-5585 3260);
PAINT MONO (-5585 3260);
FORCEPROP 0 LASTPIN (-5575 3200) $PN BJ55
J 2
(-5585 3210);
DISPLAY 0.489362 (-5585 3210);
PAINT MONO (-5585 3210);
FORCEPROP 0 LASTPIN (-5575 3150) $PN BK55
J 2
(-5585 3160);
DISPLAY 0.489362 (-5585 3160);
PAINT MONO (-5585 3160);
FORCEPROP 0 LASTPIN (-5575 3100) $PN BK56
J 2
(-5585 3110);
DISPLAY 0.489362 (-5585 3110);
PAINT MONO (-5585 3110);
FORCEPROP 0 LASTPIN (-3975 1900) $PN BY56
J 0
(-3965 1910);
DISPLAY 0.489362 (-3965 1910);
PAINT MONO (-3965 1910);
FORCEPROP 0 LASTPIN (-3975 1850) $PN CA55
J 0
(-3965 1860);
DISPLAY 0.489362 (-3965 1860);
PAINT MONO (-3965 1860);
FORCEPROP 0 LASTPIN (-3975 1800) $PN CA57
J 0
(-3965 1810);
DISPLAY 0.489362 (-3965 1810);
PAINT MONO (-3965 1810);
FORCEPROP 0 LASTPIN (-3975 1750) $PN CB55
J 0
(-3965 1760);
DISPLAY 0.489362 (-3965 1760);
PAINT MONO (-3965 1760);
FORCEPROP 0 LASTPIN (-3975 1700) $PN BT56
J 0
(-3965 1710);
DISPLAY 0.489362 (-3965 1710);
PAINT MONO (-3965 1710);
FORCEPROP 0 LASTPIN (-3975 1650) $PN BU55
J 0
(-3965 1660);
DISPLAY 0.489362 (-3965 1660);
PAINT MONO (-3965 1660);
FORCEPROP 0 LASTPIN (-3975 1600) $PN BU57
J 0
(-3965 1610);
DISPLAY 0.489362 (-3965 1610);
PAINT MONO (-3965 1610);
FORCEPROP 0 LASTPIN (-3975 1550) $PN BV55
J 0
(-3965 1560);
DISPLAY 0.489362 (-3965 1560);
PAINT MONO (-3965 1560);
FORCEPROP 0 LASTPIN (-3975 4150) $PN CB56
J 0
(-3965 4160);
DISPLAY 0.489362 (-3965 4160);
PAINT MONO (-3965 4160);
FORCEPROP 0 LASTPIN (-3975 4100) $PN CC55
J 0
(-3965 4110);
DISPLAY 0.489362 (-3965 4110);
PAINT MONO (-3965 4110);
FORCEPROP 0 LASTPIN (-3975 4050) $PN CC57
J 0
(-3965 4060);
DISPLAY 0.489362 (-3965 4060);
PAINT MONO (-3965 4060);
FORCEPROP 0 LASTPIN (-3975 4000) $PN CD55
J 0
(-3965 4010);
DISPLAY 0.489362 (-3965 4010);
PAINT MONO (-3965 4010);
FORCEPROP 0 LASTPIN (-3975 3950) $PN CF56
J 0
(-3965 3960);
DISPLAY 0.489362 (-3965 3960);
PAINT MONO (-3965 3960);
FORCEPROP 0 LASTPIN (-3975 3900) $PN CG55
J 0
(-3965 3910);
DISPLAY 0.489362 (-3965 3910);
PAINT MONO (-3965 3910);
FORCEPROP 0 LASTPIN (-3975 3850) $PN CG57
J 0
(-3965 3860);
DISPLAY 0.489362 (-3965 3860);
PAINT MONO (-3965 3860);
FORCEPROP 0 LASTPIN (-3975 3800) $PN CH55
J 0
(-3965 3810);
DISPLAY 0.489362 (-3965 3810);
PAINT MONO (-3965 3810);
FORCEPROP 0 LASTPIN (-3975 3700) $PN CH56
J 0
(-3965 3710);
DISPLAY 0.489362 (-3965 3710);
PAINT MONO (-3965 3710);
FORCEPROP 0 LASTPIN (-3975 3650) $PN CJ55
J 0
(-3965 3660);
DISPLAY 0.489362 (-3965 3660);
PAINT MONO (-3965 3660);
FORCEPROP 0 LASTPIN (-3975 3600) $PN CJ57
J 0
(-3965 3610);
DISPLAY 0.489362 (-3965 3610);
PAINT MONO (-3965 3610);
FORCEPROP 0 LASTPIN (-3975 3550) $PN CK55
J 0
(-3965 3560);
DISPLAY 0.489362 (-3965 3560);
PAINT MONO (-3965 3560);
FORCEPROP 0 LASTPIN (-3975 3500) $PN CM56
J 0
(-3965 3510);
DISPLAY 0.489362 (-3965 3510);
PAINT MONO (-3965 3510);
FORCEPROP 0 LASTPIN (-3975 3450) $PN CN55
J 0
(-3965 3460);
DISPLAY 0.489362 (-3965 3460);
PAINT MONO (-3965 3460);
FORCEPROP 0 LASTPIN (-3975 3400) $PN CN57
J 0
(-3965 3410);
DISPLAY 0.489362 (-3965 3410);
PAINT MONO (-3965 3410);
FORCEPROP 0 LASTPIN (-3975 3350) $PN CP55
J 0
(-3965 3360);
DISPLAY 0.489362 (-3965 3360);
PAINT MONO (-3965 3360);
FORCEPROP 0 LASTPIN (-3975 3250) $PN CP56
J 0
(-3965 3260);
DISPLAY 0.489362 (-3965 3260);
PAINT MONO (-3965 3260);
FORCEPROP 0 LASTPIN (-3975 3200) $PN CR55
J 0
(-3965 3210);
DISPLAY 0.489362 (-3965 3210);
PAINT MONO (-3965 3210);
FORCEPROP 0 LASTPIN (-3975 3150) $PN CR57
J 0
(-3965 3160);
DISPLAY 0.489362 (-3965 3160);
PAINT MONO (-3965 3160);
FORCEPROP 0 LASTPIN (-3975 3100) $PN CT55
J 0
(-3965 3110);
DISPLAY 0.489362 (-3965 3110);
PAINT MONO (-3965 3110);
FORCEPROP 0 LASTPIN (-3975 3050) $PN CV56
J 0
(-3965 3060);
DISPLAY 0.489362 (-3965 3060);
PAINT MONO (-3965 3060);
FORCEPROP 0 LASTPIN (-3975 3000) $PN CW55
J 0
(-3965 3010);
DISPLAY 0.489362 (-3965 3010);
PAINT MONO (-3965 3010);
FORCEPROP 0 LASTPIN (-3975 2950) $PN CW57
J 0
(-3965 2960);
DISPLAY 0.489362 (-3965 2960);
PAINT MONO (-3965 2960);
FORCEPROP 0 LASTPIN (-3975 2900) $PN CY55
J 0
(-3965 2910);
DISPLAY 0.489362 (-3965 2910);
PAINT MONO (-3965 2910);
FORCEPROP 0 LASTPIN (-3975 2800) $PN CY56
J 0
(-3965 2810);
DISPLAY 0.489362 (-3965 2810);
PAINT MONO (-3965 2810);
FORCEPROP 0 LASTPIN (-3975 2750) $PN DA55
J 0
(-3965 2760);
DISPLAY 0.489362 (-3965 2760);
PAINT MONO (-3965 2760);
FORCEPROP 0 LASTPIN (-3975 2700) $PN DA57
J 0
(-3965 2710);
DISPLAY 0.489362 (-3965 2710);
PAINT MONO (-3965 2710);
FORCEPROP 0 LASTPIN (-3975 2650) $PN DB55
J 0
(-3965 2660);
DISPLAY 0.489362 (-3965 2660);
PAINT MONO (-3965 2660);
FORCEPROP 0 LASTPIN (-3975 2600) $PN DD56
J 0
(-3965 2610);
DISPLAY 0.489362 (-3965 2610);
PAINT MONO (-3965 2610);
FORCEPROP 0 LASTPIN (-3975 2550) $PN DE55
J 0
(-3965 2560);
DISPLAY 0.489362 (-3965 2560);
PAINT MONO (-3965 2560);
FORCEPROP 0 LASTPIN (-3975 2500) $PN DE57
J 0
(-3965 2510);
DISPLAY 0.489362 (-3965 2510);
PAINT MONO (-3965 2510);
FORCEPROP 0 LASTPIN (-3975 2450) $PN DF55
J 0
(-3965 2460);
DISPLAY 0.489362 (-3965 2460);
PAINT MONO (-3965 2460);
FORCEPROP 0 LASTPIN (-5575 4900) $PN CD56
J 2
(-5585 4910);
DISPLAY 0.489362 (-5585 4910);
PAINT MONO (-5585 4910);
FORCEPROP 0 LASTPIN (-5575 4800) $PN CK56
J 2
(-5585 4810);
DISPLAY 0.489362 (-5585 4810);
PAINT MONO (-5585 4810);
FORCEPROP 0 LASTPIN (-5575 4700) $PN CT56
J 2
(-5585 4710);
DISPLAY 0.489362 (-5585 4710);
PAINT MONO (-5585 4710);
FORCEPROP 0 LASTPIN (-5575 4600) $PN DB56
J 2
(-5585 4610);
DISPLAY 0.489362 (-5585 4610);
PAINT MONO (-5585 4610);
FORCEPROP 0 LASTPIN (-5575 4500) $PN BY55
J 2
(-5585 4510);
DISPLAY 0.489362 (-5585 4510);
PAINT MONO (-5585 4510);
FORCEPROP 0 LASTPIN (-5575 4400) $PN CF55
J 2
(-5585 4410);
DISPLAY 0.489362 (-5585 4410);
PAINT MONO (-5585 4410);
FORCEPROP 0 LASTPIN (-5575 4300) $PN CM55
J 2
(-5585 4310);
DISPLAY 0.489362 (-5585 4310);
PAINT MONO (-5585 4310);
FORCEPROP 0 LASTPIN (-5575 4200) $PN CV55
J 2
(-5585 4210);
DISPLAY 0.489362 (-5585 4210);
PAINT MONO (-5585 4210);
FORCEPROP 0 LASTPIN (-5575 4100) $PN DD55
J 2
(-5585 4110);
DISPLAY 0.489362 (-5585 4110);
PAINT MONO (-5585 4110);
FORCEPROP 0 LASTPIN (-5575 4000) $PN BV56
J 2
(-5585 4010);
DISPLAY 0.489362 (-5585 4010);
PAINT MONO (-5585 4010);
FORCEPROP 0 LASTPIN (-5575 4850) $PN CE57
J 2
(-5585 4860);
DISPLAY 0.489362 (-5585 4860);
PAINT MONO (-5585 4860);
FORCEPROP 0 LASTPIN (-5575 4750) $PN CL57
J 2
(-5585 4760);
DISPLAY 0.489362 (-5585 4760);
PAINT MONO (-5585 4760);
FORCEPROP 0 LASTPIN (-5575 4650) $PN CU57
J 2
(-5585 4660);
DISPLAY 0.489362 (-5585 4660);
PAINT MONO (-5585 4660);
FORCEPROP 0 LASTPIN (-5575 4550) $PN DC57
J 2
(-5585 4560);
DISPLAY 0.489362 (-5585 4560);
PAINT MONO (-5585 4560);
FORCEPROP 0 LASTPIN (-5575 4450) $PN BW55
J 2
(-5585 4460);
DISPLAY 0.489362 (-5585 4460);
PAINT MONO (-5585 4460);
FORCEPROP 0 LASTPIN (-5575 4350) $PN CE55
J 2
(-5585 4360);
DISPLAY 0.489362 (-5585 4360);
PAINT MONO (-5585 4360);
FORCEPROP 0 LASTPIN (-5575 4250) $PN CL55
J 2
(-5585 4260);
DISPLAY 0.489362 (-5585 4260);
PAINT MONO (-5585 4260);
FORCEPROP 0 LASTPIN (-5575 4150) $PN CU55
J 2
(-5585 4160);
DISPLAY 0.489362 (-5585 4160);
PAINT MONO (-5585 4160);
FORCEPROP 0 LASTPIN (-5575 4050) $PN DC55
J 2
(-5585 4060);
DISPLAY 0.489362 (-5585 4060);
PAINT MONO (-5585 4060);
FORCEPROP 0 LASTPIN (-5575 3950) $PN BW57
J 2
(-5585 3960);
DISPLAY 0.489362 (-5585 3960);
PAINT MONO (-5585 3960);
FORCEPROP 0 LASTPIN (-5575 2200) $PN BL57
J 2
(-5585 2210);
DISPLAY 0.489362 (-5585 2210);
PAINT MONO (-5585 2210);
FORCEPROP 0 LASTPIN (-5575 1150) $PN BF55
J 2
(-5585 1160);
DISPLAY 0.489362 (-5585 1160);
PAINT MONO (-5585 1160);
FORCEPROP 2 LAST PART_TYPE SMLF
J 0
(-5400 6500);
DISPLAY 1.021277 (-5400 6500);
FORCEPROP 1 LAST MATERIAL IO
J 0
(-5420 6132);
DISPLAY 0.489362 (-5420 6132);
PAINT SKYBLUE (-5420 6132);
FORCEPROP 2 LAST VALUE SOCKET6096_13568-001
J 0
(-5400 6450);
DISPLAY 0.489362 (-5400 6450);
PAINT SKYBLUE (-5400 6450);
FORCEPROP 2 LAST CDS_LIB pure_quanta
J 0
(-4775 3575);
DISPLAY INVISIBLE (-4775 3575);
FORCEPROP 1 LAST CDS_LMAN_SYM_OUTLINE -650,2525,650,-2525
J 0
(-4775 3575);
DISPLAY 0.468085 (-4775 3575);
PAINT GREEN (-4775 3575);
DISPLAY INVISIBLE (-4775 3575);
FORCEPROP 1 LAST NEEDS_NO_SIZE TRUE
J 0
(-4775 3575);
DISPLAY 0.723404 (-4775 3575);
PAINT GREEN (-4775 3575);
DISPLAY INVISIBLE (-4775 3575);
FORCEPROP 1 LAST PATH I159
J 0
(-4775 3575);
DISPLAY 0.723404 (-4775 3575);
PAINT GREEN (-4775 3575);
DISPLAY INVISIBLE (-4775 3575);
FORCEPROP 1 LAST PART_NUMBER DGA^6000030
J 0
(-5420 6259);
DISPLAY 0.489362 (-5420 6259);
PAINT SKYBLUE (-5420 6259);
DISPLAY INVISIBLE (-5420 6259);
FORCEADD OFFPAGE..3
(-2775 5975);
FORCEPROP 2 LAST $XR0 88 
J 0
(-2561 5975);
DISPLAY 0.638298 (-2561 5975);
PAINT MONO (-2561 5975);
FORCEPROP 2 LAST CDS_LIB mstr_standard
J 0
(-2775 5975);
DISPLAY 0.723404 (-2775 5975);
PAINT MONO (-2775 5975);
DISPLAY INVISIBLE (-2775 5975);
FORCEPROP 1 LAST OFFPAGE TRUE
J 0
(-2450 5850);
DISPLAY 0.872340 (-2450 5850);
PAINT GREEN (-2450 5850);
DISPLAY INVISIBLE (-2450 5850);
FORCEPROP 1 LAST COMMENT_BODY TRUE
J 0
(-2825 5875);
DISPLAY 0.872340 (-2825 5875);
PAINT GREEN (-2825 5875);
DISPLAY INVISIBLE (-2825 5875);
FORCEPROP 2 LAST PATH I160
J 0
(-2550 6025);
DISPLAY 1.021277 (-2550 6025);
DISPLAY INVISIBLE (-2550 6025);
FORCEADD OFFPAGE..3
(-2775 4175);
FORCEPROP 2 LAST $XR0 88 
J 0
(-2561 4175);
DISPLAY 0.638298 (-2561 4175);
PAINT MONO (-2561 4175);
FORCEPROP 2 LAST CDS_LIB mstr_standard
J 0
(-2775 4175);
DISPLAY 0.723404 (-2775 4175);
PAINT MONO (-2775 4175);
DISPLAY INVISIBLE (-2775 4175);
FORCEPROP 1 LAST OFFPAGE TRUE
J 0
(-2450 4050);
DISPLAY 0.872340 (-2450 4050);
PAINT GREEN (-2450 4050);
DISPLAY INVISIBLE (-2450 4050);
FORCEPROP 1 LAST COMMENT_BODY TRUE
J 0
(-2825 4075);
DISPLAY 0.872340 (-2825 4075);
PAINT GREEN (-2825 4075);
DISPLAY INVISIBLE (-2825 4075);
FORCEPROP 2 LAST PATH I161
J 0
(-2550 4225);
DISPLAY 1.021277 (-2550 4225);
DISPLAY INVISIBLE (-2550 4225);
FORCEADD TAP..1
(-3500 5900);
FORCEPROP 3 LASTPIN (-3550 5900) SIG_NAME M_C_CPU0_SA_DQ<1>
J 0
(-3540 5910);
DISPLAY 0.659574 (-3540 5910);
PAINT MONO (-3540 5910);
DISPLAY INVISIBLE (-3540 5910);
FORCEPROP 1 LASTPIN (-3550 5900) BN 1
J 0
(-3562 5908);
DISPLAY 0.489362 (-3562 5908);
PAINT GREEN (-3562 5908);
FORCEPROP 2 LAST CDS_LIB mstr_standard
J 0
(-3500 5900);
DISPLAY 0.723404 (-3500 5900);
PAINT MONO (-3500 5900);
DISPLAY INVISIBLE (-3500 5900);
FORCEPROP 1 LAST BODY_TYPE PLUMBING
J 0
(-3500 5950);
DISPLAY 0.872340 (-3500 5950);
PAINT GREEN (-3500 5950);
DISPLAY INVISIBLE (-3500 5950);
FORCEPROP 1 LAST HDL_TAP TRUE
J 0
(-3175 5775);
DISPLAY 0.872340 (-3175 5775);
DISPLAY INVISIBLE (-3175 5775);
FORCEPROP 1 LAST PATH I162
J 0
(-3502 5900);
DISPLAY 0.872340 (-3502 5900);
PAINT GREEN (-3502 5900);
DISPLAY INVISIBLE (-3502 5900);
FORCEADD TAP..1
(-3500 5950);
FORCEPROP 3 LASTPIN (-3550 5950) SIG_NAME M_C_CPU0_SA_DQ<0>
J 0
(-3540 5960);
DISPLAY 0.659574 (-3540 5960);
PAINT MONO (-3540 5960);
DISPLAY INVISIBLE (-3540 5960);
FORCEPROP 1 LASTPIN (-3550 5950) BN 0
J 0
(-3562 5958);
DISPLAY 0.489362 (-3562 5958);
PAINT GREEN (-3562 5958);
FORCEPROP 2 LAST CDS_LIB mstr_standard
J 0
(-3500 5950);
DISPLAY 0.723404 (-3500 5950);
PAINT MONO (-3500 5950);
DISPLAY INVISIBLE (-3500 5950);
FORCEPROP 1 LAST BODY_TYPE PLUMBING
J 0
(-3500 6000);
DISPLAY 0.872340 (-3500 6000);
PAINT GREEN (-3500 6000);
DISPLAY INVISIBLE (-3500 6000);
FORCEPROP 1 LAST HDL_TAP TRUE
J 0
(-3175 5825);
DISPLAY 0.872340 (-3175 5825);
DISPLAY INVISIBLE (-3175 5825);
FORCEPROP 1 LAST PATH I163
J 0
(-3502 5950);
DISPLAY 0.872340 (-3502 5950);
PAINT GREEN (-3502 5950);
DISPLAY INVISIBLE (-3502 5950);
FORCEADD TAP..1
(-3500 5850);
FORCEPROP 3 LASTPIN (-3550 5850) SIG_NAME M_C_CPU0_SA_DQ<2>
J 0
(-3540 5860);
DISPLAY 0.659574 (-3540 5860);
PAINT MONO (-3540 5860);
DISPLAY INVISIBLE (-3540 5860);
FORCEPROP 1 LASTPIN (-3550 5850) BN 2
J 0
(-3562 5858);
DISPLAY 0.489362 (-3562 5858);
PAINT GREEN (-3562 5858);
FORCEPROP 2 LAST CDS_LIB mstr_standard
J 0
(-3500 5850);
DISPLAY 0.723404 (-3500 5850);
PAINT MONO (-3500 5850);
DISPLAY INVISIBLE (-3500 5850);
FORCEPROP 1 LAST BODY_TYPE PLUMBING
J 0
(-3500 5900);
DISPLAY 0.872340 (-3500 5900);
PAINT GREEN (-3500 5900);
DISPLAY INVISIBLE (-3500 5900);
FORCEPROP 1 LAST HDL_TAP TRUE
J 0
(-3175 5725);
DISPLAY 0.872340 (-3175 5725);
DISPLAY INVISIBLE (-3175 5725);
FORCEPROP 1 LAST PATH I164
J 0
(-3502 5850);
DISPLAY 0.872340 (-3502 5850);
PAINT GREEN (-3502 5850);
DISPLAY INVISIBLE (-3502 5850);
FORCEADD TAP..1
(-3500 5800);
FORCEPROP 3 LASTPIN (-3550 5800) SIG_NAME M_C_CPU0_SA_DQ<3>
J 0
(-3540 5810);
DISPLAY 0.659574 (-3540 5810);
PAINT MONO (-3540 5810);
DISPLAY INVISIBLE (-3540 5810);
FORCEPROP 1 LASTPIN (-3550 5800) BN 3
J 0
(-3562 5808);
DISPLAY 0.489362 (-3562 5808);
PAINT GREEN (-3562 5808);
FORCEPROP 2 LAST CDS_LIB mstr_standard
J 0
(-3500 5800);
DISPLAY 0.723404 (-3500 5800);
PAINT MONO (-3500 5800);
DISPLAY INVISIBLE (-3500 5800);
FORCEPROP 1 LAST BODY_TYPE PLUMBING
J 0
(-3500 5850);
DISPLAY 0.872340 (-3500 5850);
PAINT GREEN (-3500 5850);
DISPLAY INVISIBLE (-3500 5850);
FORCEPROP 1 LAST HDL_TAP TRUE
J 0
(-3175 5675);
DISPLAY 0.872340 (-3175 5675);
DISPLAY INVISIBLE (-3175 5675);
FORCEPROP 1 LAST PATH I165
J 0
(-3502 5800);
DISPLAY 0.872340 (-3502 5800);
PAINT GREEN (-3502 5800);
DISPLAY INVISIBLE (-3502 5800);
FORCEADD TAP..1
(-3500 5750);
FORCEPROP 3 LASTPIN (-3550 5750) SIG_NAME M_C_CPU0_SA_DQ<4>
J 0
(-3540 5760);
DISPLAY 0.659574 (-3540 5760);
PAINT MONO (-3540 5760);
DISPLAY INVISIBLE (-3540 5760);
FORCEPROP 1 LASTPIN (-3550 5750) BN 4
J 0
(-3562 5758);
DISPLAY 0.489362 (-3562 5758);
PAINT GREEN (-3562 5758);
FORCEPROP 2 LAST CDS_LIB mstr_standard
J 0
(-3500 5750);
DISPLAY 0.723404 (-3500 5750);
PAINT MONO (-3500 5750);
DISPLAY INVISIBLE (-3500 5750);
FORCEPROP 1 LAST BODY_TYPE PLUMBING
J 0
(-3500 5800);
DISPLAY 0.872340 (-3500 5800);
PAINT GREEN (-3500 5800);
DISPLAY INVISIBLE (-3500 5800);
FORCEPROP 1 LAST HDL_TAP TRUE
J 0
(-3175 5625);
DISPLAY 0.872340 (-3175 5625);
DISPLAY INVISIBLE (-3175 5625);
FORCEPROP 1 LAST PATH I166
J 0
(-3502 5750);
DISPLAY 0.872340 (-3502 5750);
PAINT GREEN (-3502 5750);
DISPLAY INVISIBLE (-3502 5750);
FORCEADD TAP..1
(-3500 5700);
FORCEPROP 3 LASTPIN (-3550 5700) SIG_NAME M_C_CPU0_SA_DQ<5>
J 0
(-3540 5710);
DISPLAY 0.659574 (-3540 5710);
PAINT MONO (-3540 5710);
DISPLAY INVISIBLE (-3540 5710);
FORCEPROP 1 LASTPIN (-3550 5700) BN 5
J 0
(-3562 5708);
DISPLAY 0.489362 (-3562 5708);
PAINT GREEN (-3562 5708);
FORCEPROP 2 LAST CDS_LIB mstr_standard
J 0
(-3500 5700);
DISPLAY 0.723404 (-3500 5700);
PAINT MONO (-3500 5700);
DISPLAY INVISIBLE (-3500 5700);
FORCEPROP 1 LAST BODY_TYPE PLUMBING
J 0
(-3500 5750);
DISPLAY 0.872340 (-3500 5750);
PAINT GREEN (-3500 5750);
DISPLAY INVISIBLE (-3500 5750);
FORCEPROP 1 LAST HDL_TAP TRUE
J 0
(-3175 5575);
DISPLAY 0.872340 (-3175 5575);
DISPLAY INVISIBLE (-3175 5575);
FORCEPROP 1 LAST PATH I167
J 0
(-3502 5700);
DISPLAY 0.872340 (-3502 5700);
PAINT GREEN (-3502 5700);
DISPLAY INVISIBLE (-3502 5700);
FORCEADD TAP..1
(-3500 5650);
FORCEPROP 3 LASTPIN (-3550 5650) SIG_NAME M_C_CPU0_SA_DQ<6>
J 0
(-3540 5660);
DISPLAY 0.659574 (-3540 5660);
PAINT MONO (-3540 5660);
DISPLAY INVISIBLE (-3540 5660);
FORCEPROP 1 LASTPIN (-3550 5650) BN 6
J 0
(-3562 5658);
DISPLAY 0.489362 (-3562 5658);
PAINT GREEN (-3562 5658);
FORCEPROP 2 LAST CDS_LIB mstr_standard
J 0
(-3500 5650);
DISPLAY 0.723404 (-3500 5650);
PAINT MONO (-3500 5650);
DISPLAY INVISIBLE (-3500 5650);
FORCEPROP 1 LAST BODY_TYPE PLUMBING
J 0
(-3500 5700);
DISPLAY 0.872340 (-3500 5700);
PAINT GREEN (-3500 5700);
DISPLAY INVISIBLE (-3500 5700);
FORCEPROP 1 LAST HDL_TAP TRUE
J 0
(-3175 5525);
DISPLAY 0.872340 (-3175 5525);
DISPLAY INVISIBLE (-3175 5525);
FORCEPROP 1 LAST PATH I168
J 0
(-3502 5650);
DISPLAY 0.872340 (-3502 5650);
PAINT GREEN (-3502 5650);
DISPLAY INVISIBLE (-3502 5650);
FORCEADD TAP..1
(-3500 5600);
FORCEPROP 3 LASTPIN (-3550 5600) SIG_NAME M_C_CPU0_SA_DQ<7>
J 0
(-3540 5610);
DISPLAY 0.659574 (-3540 5610);
PAINT MONO (-3540 5610);
DISPLAY INVISIBLE (-3540 5610);
FORCEPROP 1 LASTPIN (-3550 5600) BN 7
J 0
(-3562 5608);
DISPLAY 0.489362 (-3562 5608);
PAINT GREEN (-3562 5608);
FORCEPROP 2 LAST CDS_LIB mstr_standard
J 0
(-3500 5600);
DISPLAY 0.723404 (-3500 5600);
PAINT MONO (-3500 5600);
DISPLAY INVISIBLE (-3500 5600);
FORCEPROP 1 LAST BODY_TYPE PLUMBING
J 0
(-3500 5650);
DISPLAY 0.872340 (-3500 5650);
PAINT GREEN (-3500 5650);
DISPLAY INVISIBLE (-3500 5650);
FORCEPROP 1 LAST HDL_TAP TRUE
J 0
(-3175 5475);
DISPLAY 0.872340 (-3175 5475);
DISPLAY INVISIBLE (-3175 5475);
FORCEPROP 1 LAST PATH I169
J 0
(-3502 5600);
DISPLAY 0.872340 (-3502 5600);
PAINT GREEN (-3502 5600);
DISPLAY INVISIBLE (-3502 5600);
FORCEADD TAP..1
(-3500 5500);
FORCEPROP 3 LASTPIN (-3550 5500) SIG_NAME M_C_CPU0_SA_DQ<8>
J 0
(-3540 5510);
DISPLAY 0.659574 (-3540 5510);
PAINT MONO (-3540 5510);
DISPLAY INVISIBLE (-3540 5510);
FORCEPROP 1 LASTPIN (-3550 5500) BN 8
J 0
(-3562 5508);
DISPLAY 0.489362 (-3562 5508);
PAINT GREEN (-3562 5508);
FORCEPROP 2 LAST CDS_LIB mstr_standard
J 0
(-3500 5500);
DISPLAY 0.723404 (-3500 5500);
PAINT MONO (-3500 5500);
DISPLAY INVISIBLE (-3500 5500);
FORCEPROP 1 LAST BODY_TYPE PLUMBING
J 0
(-3500 5550);
DISPLAY 0.872340 (-3500 5550);
PAINT GREEN (-3500 5550);
DISPLAY INVISIBLE (-3500 5550);
FORCEPROP 1 LAST HDL_TAP TRUE
J 0
(-3175 5375);
DISPLAY 0.872340 (-3175 5375);
DISPLAY INVISIBLE (-3175 5375);
FORCEPROP 1 LAST PATH I170
J 0
(-3502 5500);
DISPLAY 0.872340 (-3502 5500);
PAINT GREEN (-3502 5500);
DISPLAY INVISIBLE (-3502 5500);
FORCEADD TAP..1
(-3500 5400);
FORCEPROP 3 LASTPIN (-3550 5400) SIG_NAME M_C_CPU0_SA_DQ<10>
J 0
(-3540 5410);
DISPLAY 0.659574 (-3540 5410);
PAINT MONO (-3540 5410);
DISPLAY INVISIBLE (-3540 5410);
FORCEPROP 1 LASTPIN (-3550 5400) BN 10
J 0
(-3562 5408);
DISPLAY 0.489362 (-3562 5408);
PAINT GREEN (-3562 5408);
FORCEPROP 2 LAST CDS_LIB mstr_standard
J 0
(-3500 5400);
DISPLAY 0.723404 (-3500 5400);
PAINT MONO (-3500 5400);
DISPLAY INVISIBLE (-3500 5400);
FORCEPROP 1 LAST BODY_TYPE PLUMBING
J 0
(-3500 5450);
DISPLAY 0.872340 (-3500 5450);
PAINT GREEN (-3500 5450);
DISPLAY INVISIBLE (-3500 5450);
FORCEPROP 1 LAST HDL_TAP TRUE
J 0
(-3175 5275);
DISPLAY 0.872340 (-3175 5275);
DISPLAY INVISIBLE (-3175 5275);
FORCEPROP 1 LAST PATH I171
J 0
(-3502 5400);
DISPLAY 0.872340 (-3502 5400);
PAINT GREEN (-3502 5400);
DISPLAY INVISIBLE (-3502 5400);
FORCEADD TAP..1
(-3500 5450);
FORCEPROP 3 LASTPIN (-3550 5450) SIG_NAME M_C_CPU0_SA_DQ<9>
J 0
(-3540 5460);
DISPLAY 0.659574 (-3540 5460);
PAINT MONO (-3540 5460);
DISPLAY INVISIBLE (-3540 5460);
FORCEPROP 1 LASTPIN (-3550 5450) BN 9
J 0
(-3562 5458);
DISPLAY 0.489362 (-3562 5458);
PAINT GREEN (-3562 5458);
FORCEPROP 2 LAST CDS_LIB mstr_standard
J 0
(-3500 5450);
DISPLAY 0.723404 (-3500 5450);
PAINT MONO (-3500 5450);
DISPLAY INVISIBLE (-3500 5450);
FORCEPROP 1 LAST BODY_TYPE PLUMBING
J 0
(-3500 5500);
DISPLAY 0.872340 (-3500 5500);
PAINT GREEN (-3500 5500);
DISPLAY INVISIBLE (-3500 5500);
FORCEPROP 1 LAST HDL_TAP TRUE
J 0
(-3175 5325);
DISPLAY 0.872340 (-3175 5325);
DISPLAY INVISIBLE (-3175 5325);
FORCEPROP 1 LAST PATH I172
J 0
(-3502 5450);
DISPLAY 0.872340 (-3502 5450);
PAINT GREEN (-3502 5450);
DISPLAY INVISIBLE (-3502 5450);
FORCEADD TAP..1
(-3500 5350);
FORCEPROP 3 LASTPIN (-3550 5350) SIG_NAME M_C_CPU0_SA_DQ<11>
J 0
(-3540 5360);
DISPLAY 0.659574 (-3540 5360);
PAINT MONO (-3540 5360);
DISPLAY INVISIBLE (-3540 5360);
FORCEPROP 1 LASTPIN (-3550 5350) BN 11
J 0
(-3562 5358);
DISPLAY 0.489362 (-3562 5358);
PAINT GREEN (-3562 5358);
FORCEPROP 2 LAST CDS_LIB mstr_standard
J 0
(-3500 5350);
DISPLAY 0.723404 (-3500 5350);
PAINT MONO (-3500 5350);
DISPLAY INVISIBLE (-3500 5350);
FORCEPROP 1 LAST BODY_TYPE PLUMBING
J 0
(-3500 5400);
DISPLAY 0.872340 (-3500 5400);
PAINT GREEN (-3500 5400);
DISPLAY INVISIBLE (-3500 5400);
FORCEPROP 1 LAST HDL_TAP TRUE
J 0
(-3175 5225);
DISPLAY 0.872340 (-3175 5225);
DISPLAY INVISIBLE (-3175 5225);
FORCEPROP 1 LAST PATH I173
J 0
(-3502 5350);
DISPLAY 0.872340 (-3502 5350);
PAINT GREEN (-3502 5350);
DISPLAY INVISIBLE (-3502 5350);
FORCEADD TAP..1
(-3500 5300);
FORCEPROP 3 LASTPIN (-3550 5300) SIG_NAME M_C_CPU0_SA_DQ<12>
J 0
(-3540 5310);
DISPLAY 0.659574 (-3540 5310);
PAINT MONO (-3540 5310);
DISPLAY INVISIBLE (-3540 5310);
FORCEPROP 1 LASTPIN (-3550 5300) BN 12
J 0
(-3562 5308);
DISPLAY 0.489362 (-3562 5308);
PAINT GREEN (-3562 5308);
FORCEPROP 2 LAST CDS_LIB mstr_standard
J 0
(-3500 5300);
DISPLAY 0.723404 (-3500 5300);
PAINT MONO (-3500 5300);
DISPLAY INVISIBLE (-3500 5300);
FORCEPROP 1 LAST BODY_TYPE PLUMBING
J 0
(-3500 5350);
DISPLAY 0.872340 (-3500 5350);
PAINT GREEN (-3500 5350);
DISPLAY INVISIBLE (-3500 5350);
FORCEPROP 1 LAST HDL_TAP TRUE
J 0
(-3175 5175);
DISPLAY 0.872340 (-3175 5175);
DISPLAY INVISIBLE (-3175 5175);
FORCEPROP 1 LAST PATH I174
J 0
(-3502 5300);
DISPLAY 0.872340 (-3502 5300);
PAINT GREEN (-3502 5300);
DISPLAY INVISIBLE (-3502 5300);
FORCEADD TAP..1
(-3500 5250);
FORCEPROP 3 LASTPIN (-3550 5250) SIG_NAME M_C_CPU0_SA_DQ<13>
J 0
(-3540 5260);
DISPLAY 0.659574 (-3540 5260);
PAINT MONO (-3540 5260);
DISPLAY INVISIBLE (-3540 5260);
FORCEPROP 1 LASTPIN (-3550 5250) BN 13
J 0
(-3562 5258);
DISPLAY 0.489362 (-3562 5258);
PAINT GREEN (-3562 5258);
FORCEPROP 2 LAST CDS_LIB mstr_standard
J 0
(-3500 5250);
DISPLAY 0.723404 (-3500 5250);
PAINT MONO (-3500 5250);
DISPLAY INVISIBLE (-3500 5250);
FORCEPROP 1 LAST BODY_TYPE PLUMBING
J 0
(-3500 5300);
DISPLAY 0.872340 (-3500 5300);
PAINT GREEN (-3500 5300);
DISPLAY INVISIBLE (-3500 5300);
FORCEPROP 1 LAST HDL_TAP TRUE
J 0
(-3175 5125);
DISPLAY 0.872340 (-3175 5125);
DISPLAY INVISIBLE (-3175 5125);
FORCEPROP 1 LAST PATH I175
J 0
(-3502 5250);
DISPLAY 0.872340 (-3502 5250);
PAINT GREEN (-3502 5250);
DISPLAY INVISIBLE (-3502 5250);
FORCEADD TAP..1
(-3500 5200);
FORCEPROP 3 LASTPIN (-3550 5200) SIG_NAME M_C_CPU0_SA_DQ<14>
J 0
(-3540 5210);
DISPLAY 0.659574 (-3540 5210);
PAINT MONO (-3540 5210);
DISPLAY INVISIBLE (-3540 5210);
FORCEPROP 1 LASTPIN (-3550 5200) BN 14
J 0
(-3562 5208);
DISPLAY 0.489362 (-3562 5208);
PAINT GREEN (-3562 5208);
FORCEPROP 2 LAST CDS_LIB mstr_standard
J 0
(-3500 5200);
DISPLAY 0.723404 (-3500 5200);
PAINT MONO (-3500 5200);
DISPLAY INVISIBLE (-3500 5200);
FORCEPROP 1 LAST BODY_TYPE PLUMBING
J 0
(-3500 5250);
DISPLAY 0.872340 (-3500 5250);
PAINT GREEN (-3500 5250);
DISPLAY INVISIBLE (-3500 5250);
FORCEPROP 1 LAST HDL_TAP TRUE
J 0
(-3175 5075);
DISPLAY 0.872340 (-3175 5075);
DISPLAY INVISIBLE (-3175 5075);
FORCEPROP 1 LAST PATH I176
J 0
(-3502 5200);
DISPLAY 0.872340 (-3502 5200);
PAINT GREEN (-3502 5200);
DISPLAY INVISIBLE (-3502 5200);
FORCEADD TAP..1
(-3500 5150);
FORCEPROP 3 LASTPIN (-3550 5150) SIG_NAME M_C_CPU0_SA_DQ<15>
J 0
(-3540 5160);
DISPLAY 0.659574 (-3540 5160);
PAINT MONO (-3540 5160);
DISPLAY INVISIBLE (-3540 5160);
FORCEPROP 1 LASTPIN (-3550 5150) BN 15
J 0
(-3562 5158);
DISPLAY 0.489362 (-3562 5158);
PAINT GREEN (-3562 5158);
FORCEPROP 2 LAST CDS_LIB mstr_standard
J 0
(-3500 5150);
DISPLAY 0.723404 (-3500 5150);
PAINT MONO (-3500 5150);
DISPLAY INVISIBLE (-3500 5150);
FORCEPROP 1 LAST BODY_TYPE PLUMBING
J 0
(-3500 5200);
DISPLAY 0.872340 (-3500 5200);
PAINT GREEN (-3500 5200);
DISPLAY INVISIBLE (-3500 5200);
FORCEPROP 1 LAST HDL_TAP TRUE
J 0
(-3175 5025);
DISPLAY 0.872340 (-3175 5025);
DISPLAY INVISIBLE (-3175 5025);
FORCEPROP 1 LAST PATH I177
J 0
(-3502 5150);
DISPLAY 0.872340 (-3502 5150);
PAINT GREEN (-3502 5150);
DISPLAY INVISIBLE (-3502 5150);
FORCEADD TAP..1
(-3500 5050);
FORCEPROP 3 LASTPIN (-3550 5050) SIG_NAME M_C_CPU0_SA_DQ<16>
J 0
(-3540 5060);
DISPLAY 0.659574 (-3540 5060);
PAINT MONO (-3540 5060);
DISPLAY INVISIBLE (-3540 5060);
FORCEPROP 1 LASTPIN (-3550 5050) BN 16
J 0
(-3562 5058);
DISPLAY 0.489362 (-3562 5058);
PAINT GREEN (-3562 5058);
FORCEPROP 2 LAST CDS_LIB mstr_standard
J 0
(-3500 5050);
DISPLAY 0.723404 (-3500 5050);
PAINT MONO (-3500 5050);
DISPLAY INVISIBLE (-3500 5050);
FORCEPROP 1 LAST BODY_TYPE PLUMBING
J 0
(-3500 5100);
DISPLAY 0.872340 (-3500 5100);
PAINT GREEN (-3500 5100);
DISPLAY INVISIBLE (-3500 5100);
FORCEPROP 1 LAST HDL_TAP TRUE
J 0
(-3175 4925);
DISPLAY 0.872340 (-3175 4925);
DISPLAY INVISIBLE (-3175 4925);
FORCEPROP 1 LAST PATH I178
J 0
(-3502 5050);
DISPLAY 0.872340 (-3502 5050);
PAINT GREEN (-3502 5050);
DISPLAY INVISIBLE (-3502 5050);
FORCEADD TAP..1
(-3500 5000);
FORCEPROP 3 LASTPIN (-3550 5000) SIG_NAME M_C_CPU0_SA_DQ<17>
J 0
(-3540 5010);
DISPLAY 0.659574 (-3540 5010);
PAINT MONO (-3540 5010);
DISPLAY INVISIBLE (-3540 5010);
FORCEPROP 1 LASTPIN (-3550 5000) BN 17
J 0
(-3562 5008);
DISPLAY 0.489362 (-3562 5008);
PAINT GREEN (-3562 5008);
FORCEPROP 2 LAST CDS_LIB mstr_standard
J 0
(-3500 5000);
DISPLAY 0.723404 (-3500 5000);
PAINT MONO (-3500 5000);
DISPLAY INVISIBLE (-3500 5000);
FORCEPROP 1 LAST BODY_TYPE PLUMBING
J 0
(-3500 5050);
DISPLAY 0.872340 (-3500 5050);
PAINT GREEN (-3500 5050);
DISPLAY INVISIBLE (-3500 5050);
FORCEPROP 1 LAST HDL_TAP TRUE
J 0
(-3175 4875);
DISPLAY 0.872340 (-3175 4875);
DISPLAY INVISIBLE (-3175 4875);
FORCEPROP 1 LAST PATH I179
J 0
(-3502 5000);
DISPLAY 0.872340 (-3502 5000);
PAINT GREEN (-3502 5000);
DISPLAY INVISIBLE (-3502 5000);
FORCEADD TAP..1
(-3500 4950);
FORCEPROP 3 LASTPIN (-3550 4950) SIG_NAME M_C_CPU0_SA_DQ<18>
J 0
(-3540 4960);
DISPLAY 0.659574 (-3540 4960);
PAINT MONO (-3540 4960);
DISPLAY INVISIBLE (-3540 4960);
FORCEPROP 1 LASTPIN (-3550 4950) BN 18
J 0
(-3562 4958);
DISPLAY 0.489362 (-3562 4958);
PAINT GREEN (-3562 4958);
FORCEPROP 2 LAST CDS_LIB mstr_standard
J 0
(-3500 4950);
DISPLAY 0.723404 (-3500 4950);
PAINT MONO (-3500 4950);
DISPLAY INVISIBLE (-3500 4950);
FORCEPROP 1 LAST BODY_TYPE PLUMBING
J 0
(-3500 5000);
DISPLAY 0.872340 (-3500 5000);
PAINT GREEN (-3500 5000);
DISPLAY INVISIBLE (-3500 5000);
FORCEPROP 1 LAST HDL_TAP TRUE
J 0
(-3175 4825);
DISPLAY 0.872340 (-3175 4825);
DISPLAY INVISIBLE (-3175 4825);
FORCEPROP 1 LAST PATH I180
J 0
(-3502 4950);
DISPLAY 0.872340 (-3502 4950);
PAINT GREEN (-3502 4950);
DISPLAY INVISIBLE (-3502 4950);
FORCEADD TAP..1
(-3500 4900);
FORCEPROP 3 LASTPIN (-3550 4900) SIG_NAME M_C_CPU0_SA_DQ<19>
J 0
(-3540 4910);
DISPLAY 0.659574 (-3540 4910);
PAINT MONO (-3540 4910);
DISPLAY INVISIBLE (-3540 4910);
FORCEPROP 1 LASTPIN (-3550 4900) BN 19
J 0
(-3562 4908);
DISPLAY 0.489362 (-3562 4908);
PAINT GREEN (-3562 4908);
FORCEPROP 2 LAST CDS_LIB mstr_standard
J 0
(-3500 4900);
DISPLAY 0.723404 (-3500 4900);
PAINT MONO (-3500 4900);
DISPLAY INVISIBLE (-3500 4900);
FORCEPROP 1 LAST BODY_TYPE PLUMBING
J 0
(-3500 4950);
DISPLAY 0.872340 (-3500 4950);
PAINT GREEN (-3500 4950);
DISPLAY INVISIBLE (-3500 4950);
FORCEPROP 1 LAST HDL_TAP TRUE
J 0
(-3175 4775);
DISPLAY 0.872340 (-3175 4775);
DISPLAY INVISIBLE (-3175 4775);
FORCEPROP 1 LAST PATH I181
J 0
(-3502 4900);
DISPLAY 0.872340 (-3502 4900);
PAINT GREEN (-3502 4900);
DISPLAY INVISIBLE (-3502 4900);
FORCEADD TAP..1
(-3500 4850);
FORCEPROP 3 LASTPIN (-3550 4850) SIG_NAME M_C_CPU0_SA_DQ<20>
J 0
(-3540 4860);
DISPLAY 0.659574 (-3540 4860);
PAINT MONO (-3540 4860);
DISPLAY INVISIBLE (-3540 4860);
FORCEPROP 1 LASTPIN (-3550 4850) BN 20
J 0
(-3562 4858);
DISPLAY 0.489362 (-3562 4858);
PAINT GREEN (-3562 4858);
FORCEPROP 2 LAST CDS_LIB mstr_standard
J 0
(-3500 4850);
DISPLAY 0.723404 (-3500 4850);
PAINT MONO (-3500 4850);
DISPLAY INVISIBLE (-3500 4850);
FORCEPROP 1 LAST BODY_TYPE PLUMBING
J 0
(-3500 4900);
DISPLAY 0.872340 (-3500 4900);
PAINT GREEN (-3500 4900);
DISPLAY INVISIBLE (-3500 4900);
FORCEPROP 1 LAST HDL_TAP TRUE
J 0
(-3175 4725);
DISPLAY 0.872340 (-3175 4725);
DISPLAY INVISIBLE (-3175 4725);
FORCEPROP 1 LAST PATH I182
J 0
(-3502 4850);
DISPLAY 0.872340 (-3502 4850);
PAINT GREEN (-3502 4850);
DISPLAY INVISIBLE (-3502 4850);
FORCEADD TAP..1
(-3500 4800);
FORCEPROP 3 LASTPIN (-3550 4800) SIG_NAME M_C_CPU0_SA_DQ<21>
J 0
(-3540 4810);
DISPLAY 0.659574 (-3540 4810);
PAINT MONO (-3540 4810);
DISPLAY INVISIBLE (-3540 4810);
FORCEPROP 1 LASTPIN (-3550 4800) BN 21
J 0
(-3562 4808);
DISPLAY 0.489362 (-3562 4808);
PAINT GREEN (-3562 4808);
FORCEPROP 2 LAST CDS_LIB mstr_standard
J 0
(-3500 4800);
DISPLAY 0.723404 (-3500 4800);
PAINT MONO (-3500 4800);
DISPLAY INVISIBLE (-3500 4800);
FORCEPROP 1 LAST BODY_TYPE PLUMBING
J 0
(-3500 4850);
DISPLAY 0.872340 (-3500 4850);
PAINT GREEN (-3500 4850);
DISPLAY INVISIBLE (-3500 4850);
FORCEPROP 1 LAST HDL_TAP TRUE
J 0
(-3175 4675);
DISPLAY 0.872340 (-3175 4675);
DISPLAY INVISIBLE (-3175 4675);
FORCEPROP 1 LAST PATH I183
J 0
(-3502 4800);
DISPLAY 0.872340 (-3502 4800);
PAINT GREEN (-3502 4800);
DISPLAY INVISIBLE (-3502 4800);
FORCEADD TAP..1
(-3500 4750);
FORCEPROP 3 LASTPIN (-3550 4750) SIG_NAME M_C_CPU0_SA_DQ<22>
J 0
(-3540 4760);
DISPLAY 0.659574 (-3540 4760);
PAINT MONO (-3540 4760);
DISPLAY INVISIBLE (-3540 4760);
FORCEPROP 1 LASTPIN (-3550 4750) BN 22
J 0
(-3562 4758);
DISPLAY 0.489362 (-3562 4758);
PAINT GREEN (-3562 4758);
FORCEPROP 2 LAST CDS_LIB mstr_standard
J 0
(-3500 4750);
DISPLAY 0.723404 (-3500 4750);
PAINT MONO (-3500 4750);
DISPLAY INVISIBLE (-3500 4750);
FORCEPROP 1 LAST BODY_TYPE PLUMBING
J 0
(-3500 4800);
DISPLAY 0.872340 (-3500 4800);
PAINT GREEN (-3500 4800);
DISPLAY INVISIBLE (-3500 4800);
FORCEPROP 1 LAST HDL_TAP TRUE
J 0
(-3175 4625);
DISPLAY 0.872340 (-3175 4625);
DISPLAY INVISIBLE (-3175 4625);
FORCEPROP 1 LAST PATH I184
J 0
(-3502 4750);
DISPLAY 0.872340 (-3502 4750);
PAINT GREEN (-3502 4750);
DISPLAY INVISIBLE (-3502 4750);
FORCEADD TAP..1
(-3500 4700);
FORCEPROP 3 LASTPIN (-3550 4700) SIG_NAME M_C_CPU0_SA_DQ<23>
J 0
(-3540 4710);
DISPLAY 0.659574 (-3540 4710);
PAINT MONO (-3540 4710);
DISPLAY INVISIBLE (-3540 4710);
FORCEPROP 1 LASTPIN (-3550 4700) BN 23
J 0
(-3562 4708);
DISPLAY 0.489362 (-3562 4708);
PAINT GREEN (-3562 4708);
FORCEPROP 2 LAST CDS_LIB mstr_standard
J 0
(-3500 4700);
DISPLAY 0.723404 (-3500 4700);
PAINT MONO (-3500 4700);
DISPLAY INVISIBLE (-3500 4700);
FORCEPROP 1 LAST BODY_TYPE PLUMBING
J 0
(-3500 4750);
DISPLAY 0.872340 (-3500 4750);
PAINT GREEN (-3500 4750);
DISPLAY INVISIBLE (-3500 4750);
FORCEPROP 1 LAST HDL_TAP TRUE
J 0
(-3175 4575);
DISPLAY 0.872340 (-3175 4575);
DISPLAY INVISIBLE (-3175 4575);
FORCEPROP 1 LAST PATH I185
J 0
(-3502 4700);
DISPLAY 0.872340 (-3502 4700);
PAINT GREEN (-3502 4700);
DISPLAY INVISIBLE (-3502 4700);
FORCEADD TAP..1
(-3500 4600);
FORCEPROP 3 LASTPIN (-3550 4600) SIG_NAME M_C_CPU0_SA_DQ<24>
J 0
(-3540 4610);
DISPLAY 0.659574 (-3540 4610);
PAINT MONO (-3540 4610);
DISPLAY INVISIBLE (-3540 4610);
FORCEPROP 1 LASTPIN (-3550 4600) BN 24
J 0
(-3562 4608);
DISPLAY 0.489362 (-3562 4608);
PAINT GREEN (-3562 4608);
FORCEPROP 2 LAST CDS_LIB mstr_standard
J 0
(-3500 4600);
DISPLAY 0.723404 (-3500 4600);
PAINT MONO (-3500 4600);
DISPLAY INVISIBLE (-3500 4600);
FORCEPROP 1 LAST BODY_TYPE PLUMBING
J 0
(-3500 4650);
DISPLAY 0.872340 (-3500 4650);
PAINT GREEN (-3500 4650);
DISPLAY INVISIBLE (-3500 4650);
FORCEPROP 1 LAST HDL_TAP TRUE
J 0
(-3175 4475);
DISPLAY 0.872340 (-3175 4475);
DISPLAY INVISIBLE (-3175 4475);
FORCEPROP 1 LAST PATH I186
J 0
(-3502 4600);
DISPLAY 0.872340 (-3502 4600);
PAINT GREEN (-3502 4600);
DISPLAY INVISIBLE (-3502 4600);
FORCEADD TAP..1
(-3500 4550);
FORCEPROP 3 LASTPIN (-3550 4550) SIG_NAME M_C_CPU0_SA_DQ<25>
J 0
(-3540 4560);
DISPLAY 0.659574 (-3540 4560);
PAINT MONO (-3540 4560);
DISPLAY INVISIBLE (-3540 4560);
FORCEPROP 1 LASTPIN (-3550 4550) BN 25
J 0
(-3562 4558);
DISPLAY 0.489362 (-3562 4558);
PAINT GREEN (-3562 4558);
FORCEPROP 2 LAST CDS_LIB mstr_standard
J 0
(-3500 4550);
DISPLAY 0.723404 (-3500 4550);
PAINT MONO (-3500 4550);
DISPLAY INVISIBLE (-3500 4550);
FORCEPROP 1 LAST BODY_TYPE PLUMBING
J 0
(-3500 4600);
DISPLAY 0.872340 (-3500 4600);
PAINT GREEN (-3500 4600);
DISPLAY INVISIBLE (-3500 4600);
FORCEPROP 1 LAST HDL_TAP TRUE
J 0
(-3175 4425);
DISPLAY 0.872340 (-3175 4425);
DISPLAY INVISIBLE (-3175 4425);
FORCEPROP 1 LAST PATH I187
J 0
(-3502 4550);
DISPLAY 0.872340 (-3502 4550);
PAINT GREEN (-3502 4550);
DISPLAY INVISIBLE (-3502 4550);
FORCEADD TAP..1
(-3500 4500);
FORCEPROP 3 LASTPIN (-3550 4500) SIG_NAME M_C_CPU0_SA_DQ<26>
J 0
(-3540 4510);
DISPLAY 0.659574 (-3540 4510);
PAINT MONO (-3540 4510);
DISPLAY INVISIBLE (-3540 4510);
FORCEPROP 1 LASTPIN (-3550 4500) BN 26
J 0
(-3562 4508);
DISPLAY 0.489362 (-3562 4508);
PAINT GREEN (-3562 4508);
FORCEPROP 2 LAST CDS_LIB mstr_standard
J 0
(-3500 4500);
DISPLAY 0.723404 (-3500 4500);
PAINT MONO (-3500 4500);
DISPLAY INVISIBLE (-3500 4500);
FORCEPROP 1 LAST BODY_TYPE PLUMBING
J 0
(-3500 4550);
DISPLAY 0.872340 (-3500 4550);
PAINT GREEN (-3500 4550);
DISPLAY INVISIBLE (-3500 4550);
FORCEPROP 1 LAST HDL_TAP TRUE
J 0
(-3175 4375);
DISPLAY 0.872340 (-3175 4375);
DISPLAY INVISIBLE (-3175 4375);
FORCEPROP 1 LAST PATH I188
J 0
(-3502 4500);
DISPLAY 0.872340 (-3502 4500);
PAINT GREEN (-3502 4500);
DISPLAY INVISIBLE (-3502 4500);
FORCEADD TAP..1
(-3500 4450);
FORCEPROP 3 LASTPIN (-3550 4450) SIG_NAME M_C_CPU0_SA_DQ<27>
J 0
(-3540 4460);
DISPLAY 0.659574 (-3540 4460);
PAINT MONO (-3540 4460);
DISPLAY INVISIBLE (-3540 4460);
FORCEPROP 1 LASTPIN (-3550 4450) BN 27
J 0
(-3562 4458);
DISPLAY 0.489362 (-3562 4458);
PAINT GREEN (-3562 4458);
FORCEPROP 2 LAST CDS_LIB mstr_standard
J 0
(-3500 4450);
DISPLAY 0.723404 (-3500 4450);
PAINT MONO (-3500 4450);
DISPLAY INVISIBLE (-3500 4450);
FORCEPROP 1 LAST BODY_TYPE PLUMBING
J 0
(-3500 4500);
DISPLAY 0.872340 (-3500 4500);
PAINT GREEN (-3500 4500);
DISPLAY INVISIBLE (-3500 4500);
FORCEPROP 1 LAST HDL_TAP TRUE
J 0
(-3175 4325);
DISPLAY 0.872340 (-3175 4325);
DISPLAY INVISIBLE (-3175 4325);
FORCEPROP 1 LAST PATH I189
J 0
(-3502 4450);
DISPLAY 0.872340 (-3502 4450);
PAINT GREEN (-3502 4450);
DISPLAY INVISIBLE (-3502 4450);
FORCEADD TAP..1
(-3500 4400);
FORCEPROP 3 LASTPIN (-3550 4400) SIG_NAME M_C_CPU0_SA_DQ<28>
J 0
(-3540 4410);
DISPLAY 0.659574 (-3540 4410);
PAINT MONO (-3540 4410);
DISPLAY INVISIBLE (-3540 4410);
FORCEPROP 1 LASTPIN (-3550 4400) BN 28
J 0
(-3562 4408);
DISPLAY 0.489362 (-3562 4408);
PAINT GREEN (-3562 4408);
FORCEPROP 2 LAST CDS_LIB mstr_standard
J 0
(-3500 4400);
DISPLAY 0.723404 (-3500 4400);
PAINT MONO (-3500 4400);
DISPLAY INVISIBLE (-3500 4400);
FORCEPROP 1 LAST BODY_TYPE PLUMBING
J 0
(-3500 4450);
DISPLAY 0.872340 (-3500 4450);
PAINT GREEN (-3500 4450);
DISPLAY INVISIBLE (-3500 4450);
FORCEPROP 1 LAST HDL_TAP TRUE
J 0
(-3175 4275);
DISPLAY 0.872340 (-3175 4275);
DISPLAY INVISIBLE (-3175 4275);
FORCEPROP 1 LAST PATH I190
J 0
(-3502 4400);
DISPLAY 0.872340 (-3502 4400);
PAINT GREEN (-3502 4400);
DISPLAY INVISIBLE (-3502 4400);
FORCEADD TAP..1
(-3500 4350);
FORCEPROP 3 LASTPIN (-3550 4350) SIG_NAME M_C_CPU0_SA_DQ<29>
J 0
(-3540 4360);
DISPLAY 0.659574 (-3540 4360);
PAINT MONO (-3540 4360);
DISPLAY INVISIBLE (-3540 4360);
FORCEPROP 1 LASTPIN (-3550 4350) BN 29
J 0
(-3562 4358);
DISPLAY 0.489362 (-3562 4358);
PAINT GREEN (-3562 4358);
FORCEPROP 2 LAST CDS_LIB mstr_standard
J 0
(-3500 4350);
DISPLAY 0.723404 (-3500 4350);
PAINT MONO (-3500 4350);
DISPLAY INVISIBLE (-3500 4350);
FORCEPROP 1 LAST BODY_TYPE PLUMBING
J 0
(-3500 4400);
DISPLAY 0.872340 (-3500 4400);
PAINT GREEN (-3500 4400);
DISPLAY INVISIBLE (-3500 4400);
FORCEPROP 1 LAST HDL_TAP TRUE
J 0
(-3175 4225);
DISPLAY 0.872340 (-3175 4225);
DISPLAY INVISIBLE (-3175 4225);
FORCEPROP 1 LAST PATH I191
J 0
(-3502 4350);
DISPLAY 0.872340 (-3502 4350);
PAINT GREEN (-3502 4350);
DISPLAY INVISIBLE (-3502 4350);
FORCEADD TAP..1
(-3500 4300);
FORCEPROP 3 LASTPIN (-3550 4300) SIG_NAME M_C_CPU0_SA_DQ<30>
J 0
(-3540 4310);
DISPLAY 0.659574 (-3540 4310);
PAINT MONO (-3540 4310);
DISPLAY INVISIBLE (-3540 4310);
FORCEPROP 1 LASTPIN (-3550 4300) BN 30
J 0
(-3562 4308);
DISPLAY 0.489362 (-3562 4308);
PAINT GREEN (-3562 4308);
FORCEPROP 2 LAST CDS_LIB mstr_standard
J 0
(-3500 4300);
DISPLAY 0.723404 (-3500 4300);
PAINT MONO (-3500 4300);
DISPLAY INVISIBLE (-3500 4300);
FORCEPROP 1 LAST BODY_TYPE PLUMBING
J 0
(-3500 4350);
DISPLAY 0.872340 (-3500 4350);
PAINT GREEN (-3500 4350);
DISPLAY INVISIBLE (-3500 4350);
FORCEPROP 1 LAST HDL_TAP TRUE
J 0
(-3175 4175);
DISPLAY 0.872340 (-3175 4175);
DISPLAY INVISIBLE (-3175 4175);
FORCEPROP 1 LAST PATH I192
J 0
(-3502 4300);
DISPLAY 0.872340 (-3502 4300);
PAINT GREEN (-3502 4300);
DISPLAY INVISIBLE (-3502 4300);
FORCEADD TAP..1
(-3500 4250);
FORCEPROP 3 LASTPIN (-3550 4250) SIG_NAME M_C_CPU0_SA_DQ<31>
J 0
(-3540 4260);
DISPLAY 0.659574 (-3540 4260);
PAINT MONO (-3540 4260);
DISPLAY INVISIBLE (-3540 4260);
FORCEPROP 1 LASTPIN (-3550 4250) BN 31
J 0
(-3562 4258);
DISPLAY 0.489362 (-3562 4258);
PAINT GREEN (-3562 4258);
FORCEPROP 2 LAST CDS_LIB mstr_standard
J 0
(-3500 4250);
DISPLAY 0.723404 (-3500 4250);
PAINT MONO (-3500 4250);
DISPLAY INVISIBLE (-3500 4250);
FORCEPROP 1 LAST BODY_TYPE PLUMBING
J 0
(-3500 4300);
DISPLAY 0.872340 (-3500 4300);
PAINT GREEN (-3500 4300);
DISPLAY INVISIBLE (-3500 4300);
FORCEPROP 1 LAST HDL_TAP TRUE
J 0
(-3175 4125);
DISPLAY 0.872340 (-3175 4125);
DISPLAY INVISIBLE (-3175 4125);
FORCEPROP 1 LAST PATH I193
J 0
(-3502 4250);
DISPLAY 0.872340 (-3502 4250);
PAINT GREEN (-3502 4250);
DISPLAY INVISIBLE (-3502 4250);
FORCEADD TAP..1
(-3500 4100);
FORCEPROP 3 LASTPIN (-3550 4100) SIG_NAME M_C_CPU0_SB_DQ<1>
J 0
(-3540 4110);
DISPLAY 0.659574 (-3540 4110);
PAINT MONO (-3540 4110);
DISPLAY INVISIBLE (-3540 4110);
FORCEPROP 1 LASTPIN (-3550 4100) BN 1
J 0
(-3562 4108);
DISPLAY 0.489362 (-3562 4108);
PAINT GREEN (-3562 4108);
FORCEPROP 2 LAST CDS_LIB mstr_standard
J 0
(-3500 4100);
DISPLAY 0.723404 (-3500 4100);
PAINT MONO (-3500 4100);
DISPLAY INVISIBLE (-3500 4100);
FORCEPROP 1 LAST BODY_TYPE PLUMBING
J 0
(-3500 4150);
DISPLAY 0.872340 (-3500 4150);
PAINT GREEN (-3500 4150);
DISPLAY INVISIBLE (-3500 4150);
FORCEPROP 1 LAST HDL_TAP TRUE
J 0
(-3175 3975);
DISPLAY 0.872340 (-3175 3975);
DISPLAY INVISIBLE (-3175 3975);
FORCEPROP 1 LAST PATH I194
J 0
(-3502 4100);
DISPLAY 0.872340 (-3502 4100);
PAINT GREEN (-3502 4100);
DISPLAY INVISIBLE (-3502 4100);
FORCEADD TAP..1
(-3500 4150);
FORCEPROP 3 LASTPIN (-3550 4150) SIG_NAME M_C_CPU0_SB_DQ<0>
J 0
(-3540 4160);
DISPLAY 0.659574 (-3540 4160);
PAINT MONO (-3540 4160);
DISPLAY INVISIBLE (-3540 4160);
FORCEPROP 1 LASTPIN (-3550 4150) BN 0
J 0
(-3562 4158);
DISPLAY 0.489362 (-3562 4158);
PAINT GREEN (-3562 4158);
FORCEPROP 2 LAST CDS_LIB mstr_standard
J 0
(-3500 4150);
DISPLAY 0.723404 (-3500 4150);
PAINT MONO (-3500 4150);
DISPLAY INVISIBLE (-3500 4150);
FORCEPROP 1 LAST BODY_TYPE PLUMBING
J 0
(-3500 4200);
DISPLAY 0.872340 (-3500 4200);
PAINT GREEN (-3500 4200);
DISPLAY INVISIBLE (-3500 4200);
FORCEPROP 1 LAST HDL_TAP TRUE
J 0
(-3175 4025);
DISPLAY 0.872340 (-3175 4025);
DISPLAY INVISIBLE (-3175 4025);
FORCEPROP 1 LAST PATH I195
J 0
(-3502 4150);
DISPLAY 0.872340 (-3502 4150);
PAINT GREEN (-3502 4150);
DISPLAY INVISIBLE (-3502 4150);
FORCEADD OFFPAGE..6
R 2
(-2900 2400);
FORCEPROP 2 LAST $XR0 88 
J 0
(-2686 2400);
DISPLAY 0.638298 (-2686 2400);
PAINT MONO (-2686 2400);
FORCEPROP 2 LAST CDS_LIB mstr_standard
J 2
(-2900 2400);
DISPLAY 0.723404 (-2900 2400);
PAINT MONO (-2900 2400);
DISPLAY INVISIBLE (-2900 2400);
FORCEPROP 1 LAST OFFPAGE TRUE
J 2
(-3225 2275);
DISPLAY 0.872340 (-3225 2275);
PAINT GREEN (-3225 2275);
DISPLAY INVISIBLE (-3225 2275);
FORCEPROP 1 LAST COMMENT_BODY TRUE
J 2
(-3000 2325);
DISPLAY 0.872340 (-3000 2325);
PAINT GREEN (-3000 2325);
DISPLAY INVISIBLE (-3000 2325);
FORCEPROP 2 LAST PATH I196
J 0
(-2675 2450);
DISPLAY 1.021277 (-2675 2450);
DISPLAY INVISIBLE (-2675 2450);
FORCEADD TAP..1
(-3500 4050);
FORCEPROP 3 LASTPIN (-3550 4050) SIG_NAME M_C_CPU0_SB_DQ<2>
J 0
(-3540 4060);
DISPLAY 0.659574 (-3540 4060);
PAINT MONO (-3540 4060);
DISPLAY INVISIBLE (-3540 4060);
FORCEPROP 1 LASTPIN (-3550 4050) BN 2
J 0
(-3562 4058);
DISPLAY 0.489362 (-3562 4058);
PAINT GREEN (-3562 4058);
FORCEPROP 2 LAST CDS_LIB mstr_standard
J 0
(-3500 4050);
DISPLAY 0.723404 (-3500 4050);
PAINT MONO (-3500 4050);
DISPLAY INVISIBLE (-3500 4050);
FORCEPROP 1 LAST BODY_TYPE PLUMBING
J 0
(-3500 4100);
DISPLAY 0.872340 (-3500 4100);
PAINT GREEN (-3500 4100);
DISPLAY INVISIBLE (-3500 4100);
FORCEPROP 1 LAST HDL_TAP TRUE
J 0
(-3175 3925);
DISPLAY 0.872340 (-3175 3925);
DISPLAY INVISIBLE (-3175 3925);
FORCEPROP 1 LAST PATH I197
J 0
(-3502 4050);
DISPLAY 0.872340 (-3502 4050);
PAINT GREEN (-3502 4050);
DISPLAY INVISIBLE (-3502 4050);
FORCEADD TAP..1
(-3500 4000);
FORCEPROP 3 LASTPIN (-3550 4000) SIG_NAME M_C_CPU0_SB_DQ<3>
J 0
(-3540 4010);
DISPLAY 0.659574 (-3540 4010);
PAINT MONO (-3540 4010);
DISPLAY INVISIBLE (-3540 4010);
FORCEPROP 1 LASTPIN (-3550 4000) BN 3
J 0
(-3562 4008);
DISPLAY 0.489362 (-3562 4008);
PAINT GREEN (-3562 4008);
FORCEPROP 2 LAST CDS_LIB mstr_standard
J 0
(-3500 4000);
DISPLAY 0.723404 (-3500 4000);
PAINT MONO (-3500 4000);
DISPLAY INVISIBLE (-3500 4000);
FORCEPROP 1 LAST BODY_TYPE PLUMBING
J 0
(-3500 4050);
DISPLAY 0.872340 (-3500 4050);
PAINT GREEN (-3500 4050);
DISPLAY INVISIBLE (-3500 4050);
FORCEPROP 1 LAST HDL_TAP TRUE
J 0
(-3175 3875);
DISPLAY 0.872340 (-3175 3875);
DISPLAY INVISIBLE (-3175 3875);
FORCEPROP 1 LAST PATH I198
J 0
(-3502 4000);
DISPLAY 0.872340 (-3502 4000);
PAINT GREEN (-3502 4000);
DISPLAY INVISIBLE (-3502 4000);
FORCEADD TAP..1
(-3500 3950);
FORCEPROP 3 LASTPIN (-3550 3950) SIG_NAME M_C_CPU0_SB_DQ<4>
J 0
(-3540 3960);
DISPLAY 0.659574 (-3540 3960);
PAINT MONO (-3540 3960);
DISPLAY INVISIBLE (-3540 3960);
FORCEPROP 1 LASTPIN (-3550 3950) BN 4
J 0
(-3562 3958);
DISPLAY 0.489362 (-3562 3958);
PAINT GREEN (-3562 3958);
FORCEPROP 2 LAST CDS_LIB mstr_standard
J 0
(-3500 3950);
DISPLAY 0.723404 (-3500 3950);
PAINT MONO (-3500 3950);
DISPLAY INVISIBLE (-3500 3950);
FORCEPROP 1 LAST BODY_TYPE PLUMBING
J 0
(-3500 4000);
DISPLAY 0.872340 (-3500 4000);
PAINT GREEN (-3500 4000);
DISPLAY INVISIBLE (-3500 4000);
FORCEPROP 1 LAST HDL_TAP TRUE
J 0
(-3175 3825);
DISPLAY 0.872340 (-3175 3825);
DISPLAY INVISIBLE (-3175 3825);
FORCEPROP 1 LAST PATH I199
J 0
(-3502 3950);
DISPLAY 0.872340 (-3502 3950);
PAINT GREEN (-3502 3950);
DISPLAY INVISIBLE (-3502 3950);
FORCEADD TAP..1
(-3500 3900);
FORCEPROP 3 LASTPIN (-3550 3900) SIG_NAME M_C_CPU0_SB_DQ<5>
J 0
(-3540 3910);
DISPLAY 0.659574 (-3540 3910);
PAINT MONO (-3540 3910);
DISPLAY INVISIBLE (-3540 3910);
FORCEPROP 1 LASTPIN (-3550 3900) BN 5
J 0
(-3562 3908);
DISPLAY 0.489362 (-3562 3908);
PAINT GREEN (-3562 3908);
FORCEPROP 2 LAST CDS_LIB mstr_standard
J 0
(-3500 3900);
DISPLAY 0.723404 (-3500 3900);
PAINT MONO (-3500 3900);
DISPLAY INVISIBLE (-3500 3900);
FORCEPROP 1 LAST BODY_TYPE PLUMBING
J 0
(-3500 3950);
DISPLAY 0.872340 (-3500 3950);
PAINT GREEN (-3500 3950);
DISPLAY INVISIBLE (-3500 3950);
FORCEPROP 1 LAST HDL_TAP TRUE
J 0
(-3175 3775);
DISPLAY 0.872340 (-3175 3775);
DISPLAY INVISIBLE (-3175 3775);
FORCEPROP 1 LAST PATH I200
J 0
(-3502 3900);
DISPLAY 0.872340 (-3502 3900);
PAINT GREEN (-3502 3900);
DISPLAY INVISIBLE (-3502 3900);
FORCEADD TAP..1
(-3500 3850);
FORCEPROP 3 LASTPIN (-3550 3850) SIG_NAME M_C_CPU0_SB_DQ<6>
J 0
(-3540 3860);
DISPLAY 0.659574 (-3540 3860);
PAINT MONO (-3540 3860);
DISPLAY INVISIBLE (-3540 3860);
FORCEPROP 1 LASTPIN (-3550 3850) BN 6
J 0
(-3562 3858);
DISPLAY 0.489362 (-3562 3858);
PAINT GREEN (-3562 3858);
FORCEPROP 2 LAST CDS_LIB mstr_standard
J 0
(-3500 3850);
DISPLAY 0.723404 (-3500 3850);
PAINT MONO (-3500 3850);
DISPLAY INVISIBLE (-3500 3850);
FORCEPROP 1 LAST BODY_TYPE PLUMBING
J 0
(-3500 3900);
DISPLAY 0.872340 (-3500 3900);
PAINT GREEN (-3500 3900);
DISPLAY INVISIBLE (-3500 3900);
FORCEPROP 1 LAST HDL_TAP TRUE
J 0
(-3175 3725);
DISPLAY 0.872340 (-3175 3725);
DISPLAY INVISIBLE (-3175 3725);
FORCEPROP 1 LAST PATH I201
J 0
(-3502 3850);
DISPLAY 0.872340 (-3502 3850);
PAINT GREEN (-3502 3850);
DISPLAY INVISIBLE (-3502 3850);
FORCEADD TAP..1
(-3500 3800);
FORCEPROP 3 LASTPIN (-3550 3800) SIG_NAME M_C_CPU0_SB_DQ<7>
J 0
(-3540 3810);
DISPLAY 0.659574 (-3540 3810);
PAINT MONO (-3540 3810);
DISPLAY INVISIBLE (-3540 3810);
FORCEPROP 1 LASTPIN (-3550 3800) BN 7
J 0
(-3562 3808);
DISPLAY 0.489362 (-3562 3808);
PAINT GREEN (-3562 3808);
FORCEPROP 2 LAST CDS_LIB mstr_standard
J 0
(-3500 3800);
DISPLAY 0.723404 (-3500 3800);
PAINT MONO (-3500 3800);
DISPLAY INVISIBLE (-3500 3800);
FORCEPROP 1 LAST BODY_TYPE PLUMBING
J 0
(-3500 3850);
DISPLAY 0.872340 (-3500 3850);
PAINT GREEN (-3500 3850);
DISPLAY INVISIBLE (-3500 3850);
FORCEPROP 1 LAST HDL_TAP TRUE
J 0
(-3175 3675);
DISPLAY 0.872340 (-3175 3675);
DISPLAY INVISIBLE (-3175 3675);
FORCEPROP 1 LAST PATH I202
J 0
(-3502 3800);
DISPLAY 0.872340 (-3502 3800);
PAINT GREEN (-3502 3800);
DISPLAY INVISIBLE (-3502 3800);
FORCEADD TAP..1
(-3500 3700);
FORCEPROP 3 LASTPIN (-3550 3700) SIG_NAME M_C_CPU0_SB_DQ<8>
J 0
(-3540 3710);
DISPLAY 0.659574 (-3540 3710);
PAINT MONO (-3540 3710);
DISPLAY INVISIBLE (-3540 3710);
FORCEPROP 1 LASTPIN (-3550 3700) BN 8
J 0
(-3562 3708);
DISPLAY 0.489362 (-3562 3708);
PAINT GREEN (-3562 3708);
FORCEPROP 2 LAST CDS_LIB mstr_standard
J 0
(-3500 3700);
DISPLAY 0.723404 (-3500 3700);
PAINT MONO (-3500 3700);
DISPLAY INVISIBLE (-3500 3700);
FORCEPROP 1 LAST BODY_TYPE PLUMBING
J 0
(-3500 3750);
DISPLAY 0.872340 (-3500 3750);
PAINT GREEN (-3500 3750);
DISPLAY INVISIBLE (-3500 3750);
FORCEPROP 1 LAST HDL_TAP TRUE
J 0
(-3175 3575);
DISPLAY 0.872340 (-3175 3575);
DISPLAY INVISIBLE (-3175 3575);
FORCEPROP 1 LAST PATH I203
J 0
(-3502 3700);
DISPLAY 0.872340 (-3502 3700);
PAINT GREEN (-3502 3700);
DISPLAY INVISIBLE (-3502 3700);
FORCEADD TAP..1
(-3500 3650);
FORCEPROP 3 LASTPIN (-3550 3650) SIG_NAME M_C_CPU0_SB_DQ<9>
J 0
(-3540 3660);
DISPLAY 0.659574 (-3540 3660);
PAINT MONO (-3540 3660);
DISPLAY INVISIBLE (-3540 3660);
FORCEPROP 1 LASTPIN (-3550 3650) BN 9
J 0
(-3562 3658);
DISPLAY 0.489362 (-3562 3658);
PAINT GREEN (-3562 3658);
FORCEPROP 2 LAST CDS_LIB mstr_standard
J 0
(-3500 3650);
DISPLAY 0.723404 (-3500 3650);
PAINT MONO (-3500 3650);
DISPLAY INVISIBLE (-3500 3650);
FORCEPROP 1 LAST BODY_TYPE PLUMBING
J 0
(-3500 3700);
DISPLAY 0.872340 (-3500 3700);
PAINT GREEN (-3500 3700);
DISPLAY INVISIBLE (-3500 3700);
FORCEPROP 1 LAST HDL_TAP TRUE
J 0
(-3175 3525);
DISPLAY 0.872340 (-3175 3525);
DISPLAY INVISIBLE (-3175 3525);
FORCEPROP 1 LAST PATH I204
J 0
(-3502 3650);
DISPLAY 0.872340 (-3502 3650);
PAINT GREEN (-3502 3650);
DISPLAY INVISIBLE (-3502 3650);
FORCEADD TAP..1
(-3500 3600);
FORCEPROP 3 LASTPIN (-3550 3600) SIG_NAME M_C_CPU0_SB_DQ<10>
J 0
(-3540 3610);
DISPLAY 0.659574 (-3540 3610);
PAINT MONO (-3540 3610);
DISPLAY INVISIBLE (-3540 3610);
FORCEPROP 1 LASTPIN (-3550 3600) BN 10
J 0
(-3562 3608);
DISPLAY 0.489362 (-3562 3608);
PAINT GREEN (-3562 3608);
FORCEPROP 2 LAST CDS_LIB mstr_standard
J 0
(-3500 3600);
DISPLAY 0.723404 (-3500 3600);
PAINT MONO (-3500 3600);
DISPLAY INVISIBLE (-3500 3600);
FORCEPROP 1 LAST BODY_TYPE PLUMBING
J 0
(-3500 3650);
DISPLAY 0.872340 (-3500 3650);
PAINT GREEN (-3500 3650);
DISPLAY INVISIBLE (-3500 3650);
FORCEPROP 1 LAST HDL_TAP TRUE
J 0
(-3175 3475);
DISPLAY 0.872340 (-3175 3475);
DISPLAY INVISIBLE (-3175 3475);
FORCEPROP 1 LAST PATH I205
J 0
(-3502 3600);
DISPLAY 0.872340 (-3502 3600);
PAINT GREEN (-3502 3600);
DISPLAY INVISIBLE (-3502 3600);
FORCEADD TAP..1
(-3500 3550);
FORCEPROP 3 LASTPIN (-3550 3550) SIG_NAME M_C_CPU0_SB_DQ<11>
J 0
(-3540 3560);
DISPLAY 0.659574 (-3540 3560);
PAINT MONO (-3540 3560);
DISPLAY INVISIBLE (-3540 3560);
FORCEPROP 1 LASTPIN (-3550 3550) BN 11
J 0
(-3562 3558);
DISPLAY 0.489362 (-3562 3558);
PAINT GREEN (-3562 3558);
FORCEPROP 2 LAST CDS_LIB mstr_standard
J 0
(-3500 3550);
DISPLAY 0.723404 (-3500 3550);
PAINT MONO (-3500 3550);
DISPLAY INVISIBLE (-3500 3550);
FORCEPROP 1 LAST BODY_TYPE PLUMBING
J 0
(-3500 3600);
DISPLAY 0.872340 (-3500 3600);
PAINT GREEN (-3500 3600);
DISPLAY INVISIBLE (-3500 3600);
FORCEPROP 1 LAST HDL_TAP TRUE
J 0
(-3175 3425);
DISPLAY 0.872340 (-3175 3425);
DISPLAY INVISIBLE (-3175 3425);
FORCEPROP 1 LAST PATH I206
J 0
(-3502 3550);
DISPLAY 0.872340 (-3502 3550);
PAINT GREEN (-3502 3550);
DISPLAY INVISIBLE (-3502 3550);
FORCEADD TAP..1
(-3500 3500);
FORCEPROP 3 LASTPIN (-3550 3500) SIG_NAME M_C_CPU0_SB_DQ<12>
J 0
(-3540 3510);
DISPLAY 0.659574 (-3540 3510);
PAINT MONO (-3540 3510);
DISPLAY INVISIBLE (-3540 3510);
FORCEPROP 1 LASTPIN (-3550 3500) BN 12
J 0
(-3562 3508);
DISPLAY 0.489362 (-3562 3508);
PAINT GREEN (-3562 3508);
FORCEPROP 2 LAST CDS_LIB mstr_standard
J 0
(-3500 3500);
DISPLAY 0.723404 (-3500 3500);
PAINT MONO (-3500 3500);
DISPLAY INVISIBLE (-3500 3500);
FORCEPROP 1 LAST BODY_TYPE PLUMBING
J 0
(-3500 3550);
DISPLAY 0.872340 (-3500 3550);
PAINT GREEN (-3500 3550);
DISPLAY INVISIBLE (-3500 3550);
FORCEPROP 1 LAST HDL_TAP TRUE
J 0
(-3175 3375);
DISPLAY 0.872340 (-3175 3375);
DISPLAY INVISIBLE (-3175 3375);
FORCEPROP 1 LAST PATH I207
J 0
(-3502 3500);
DISPLAY 0.872340 (-3502 3500);
PAINT GREEN (-3502 3500);
DISPLAY INVISIBLE (-3502 3500);
FORCEADD TAP..1
(-3500 3400);
FORCEPROP 3 LASTPIN (-3550 3400) SIG_NAME M_C_CPU0_SB_DQ<14>
J 0
(-3540 3410);
DISPLAY 0.659574 (-3540 3410);
PAINT MONO (-3540 3410);
DISPLAY INVISIBLE (-3540 3410);
FORCEPROP 1 LASTPIN (-3550 3400) BN 14
J 0
(-3562 3408);
DISPLAY 0.489362 (-3562 3408);
PAINT GREEN (-3562 3408);
FORCEPROP 2 LAST CDS_LIB mstr_standard
J 0
(-3500 3400);
DISPLAY 0.723404 (-3500 3400);
PAINT MONO (-3500 3400);
DISPLAY INVISIBLE (-3500 3400);
FORCEPROP 1 LAST BODY_TYPE PLUMBING
J 0
(-3500 3450);
DISPLAY 0.872340 (-3500 3450);
PAINT GREEN (-3500 3450);
DISPLAY INVISIBLE (-3500 3450);
FORCEPROP 1 LAST HDL_TAP TRUE
J 0
(-3175 3275);
DISPLAY 0.872340 (-3175 3275);
DISPLAY INVISIBLE (-3175 3275);
FORCEPROP 1 LAST PATH I208
J 0
(-3502 3400);
DISPLAY 0.872340 (-3502 3400);
PAINT GREEN (-3502 3400);
DISPLAY INVISIBLE (-3502 3400);
FORCEADD TAP..1
(-3500 3350);
FORCEPROP 3 LASTPIN (-3550 3350) SIG_NAME M_C_CPU0_SB_DQ<15>
J 0
(-3540 3360);
DISPLAY 0.659574 (-3540 3360);
PAINT MONO (-3540 3360);
DISPLAY INVISIBLE (-3540 3360);
FORCEPROP 1 LASTPIN (-3550 3350) BN 15
J 0
(-3562 3358);
DISPLAY 0.489362 (-3562 3358);
PAINT GREEN (-3562 3358);
FORCEPROP 2 LAST CDS_LIB mstr_standard
J 0
(-3500 3350);
DISPLAY 0.723404 (-3500 3350);
PAINT MONO (-3500 3350);
DISPLAY INVISIBLE (-3500 3350);
FORCEPROP 1 LAST BODY_TYPE PLUMBING
J 0
(-3500 3400);
DISPLAY 0.872340 (-3500 3400);
PAINT GREEN (-3500 3400);
DISPLAY INVISIBLE (-3500 3400);
FORCEPROP 1 LAST HDL_TAP TRUE
J 0
(-3175 3225);
DISPLAY 0.872340 (-3175 3225);
DISPLAY INVISIBLE (-3175 3225);
FORCEPROP 1 LAST PATH I209
J 0
(-3502 3350);
DISPLAY 0.872340 (-3502 3350);
PAINT GREEN (-3502 3350);
DISPLAY INVISIBLE (-3502 3350);
FORCEADD TAP..1
(-3500 3450);
FORCEPROP 3 LASTPIN (-3550 3450) SIG_NAME M_C_CPU0_SB_DQ<13>
J 0
(-3540 3460);
DISPLAY 0.659574 (-3540 3460);
PAINT MONO (-3540 3460);
DISPLAY INVISIBLE (-3540 3460);
FORCEPROP 1 LASTPIN (-3550 3450) BN 13
J 0
(-3562 3458);
DISPLAY 0.489362 (-3562 3458);
PAINT GREEN (-3562 3458);
FORCEPROP 2 LAST CDS_LIB mstr_standard
J 0
(-3500 3450);
DISPLAY 0.723404 (-3500 3450);
PAINT MONO (-3500 3450);
DISPLAY INVISIBLE (-3500 3450);
FORCEPROP 1 LAST BODY_TYPE PLUMBING
J 0
(-3500 3500);
DISPLAY 0.872340 (-3500 3500);
PAINT GREEN (-3500 3500);
DISPLAY INVISIBLE (-3500 3500);
FORCEPROP 1 LAST HDL_TAP TRUE
J 0
(-3175 3325);
DISPLAY 0.872340 (-3175 3325);
DISPLAY INVISIBLE (-3175 3325);
FORCEPROP 1 LAST PATH I210
J 0
(-3502 3450);
DISPLAY 0.872340 (-3502 3450);
PAINT GREEN (-3502 3450);
DISPLAY INVISIBLE (-3502 3450);
FORCEADD TAP..1
(-3500 3250);
FORCEPROP 3 LASTPIN (-3550 3250) SIG_NAME M_C_CPU0_SB_DQ<16>
J 0
(-3540 3260);
DISPLAY 0.659574 (-3540 3260);
PAINT MONO (-3540 3260);
DISPLAY INVISIBLE (-3540 3260);
FORCEPROP 1 LASTPIN (-3550 3250) BN 16
J 0
(-3562 3258);
DISPLAY 0.489362 (-3562 3258);
PAINT GREEN (-3562 3258);
FORCEPROP 2 LAST CDS_LIB mstr_standard
J 0
(-3500 3250);
DISPLAY 0.723404 (-3500 3250);
PAINT MONO (-3500 3250);
DISPLAY INVISIBLE (-3500 3250);
FORCEPROP 1 LAST BODY_TYPE PLUMBING
J 0
(-3500 3300);
DISPLAY 0.872340 (-3500 3300);
PAINT GREEN (-3500 3300);
DISPLAY INVISIBLE (-3500 3300);
FORCEPROP 1 LAST HDL_TAP TRUE
J 0
(-3175 3125);
DISPLAY 0.872340 (-3175 3125);
DISPLAY INVISIBLE (-3175 3125);
FORCEPROP 1 LAST PATH I211
J 0
(-3502 3250);
DISPLAY 0.872340 (-3502 3250);
PAINT GREEN (-3502 3250);
DISPLAY INVISIBLE (-3502 3250);
FORCEADD TAP..1
(-3500 3200);
FORCEPROP 3 LASTPIN (-3550 3200) SIG_NAME M_C_CPU0_SB_DQ<17>
J 0
(-3540 3210);
DISPLAY 0.659574 (-3540 3210);
PAINT MONO (-3540 3210);
DISPLAY INVISIBLE (-3540 3210);
FORCEPROP 1 LASTPIN (-3550 3200) BN 17
J 0
(-3562 3208);
DISPLAY 0.489362 (-3562 3208);
PAINT GREEN (-3562 3208);
FORCEPROP 2 LAST CDS_LIB mstr_standard
J 0
(-3500 3200);
DISPLAY 0.723404 (-3500 3200);
PAINT MONO (-3500 3200);
DISPLAY INVISIBLE (-3500 3200);
FORCEPROP 1 LAST BODY_TYPE PLUMBING
J 0
(-3500 3250);
DISPLAY 0.872340 (-3500 3250);
PAINT GREEN (-3500 3250);
DISPLAY INVISIBLE (-3500 3250);
FORCEPROP 1 LAST HDL_TAP TRUE
J 0
(-3175 3075);
DISPLAY 0.872340 (-3175 3075);
DISPLAY INVISIBLE (-3175 3075);
FORCEPROP 1 LAST PATH I212
J 0
(-3502 3200);
DISPLAY 0.872340 (-3502 3200);
PAINT GREEN (-3502 3200);
DISPLAY INVISIBLE (-3502 3200);
FORCEADD TAP..1
(-3500 3150);
FORCEPROP 3 LASTPIN (-3550 3150) SIG_NAME M_C_CPU0_SB_DQ<18>
J 0
(-3540 3160);
DISPLAY 0.659574 (-3540 3160);
PAINT MONO (-3540 3160);
DISPLAY INVISIBLE (-3540 3160);
FORCEPROP 1 LASTPIN (-3550 3150) BN 18
J 0
(-3562 3158);
DISPLAY 0.489362 (-3562 3158);
PAINT GREEN (-3562 3158);
FORCEPROP 2 LAST CDS_LIB mstr_standard
J 0
(-3500 3150);
DISPLAY 0.723404 (-3500 3150);
PAINT MONO (-3500 3150);
DISPLAY INVISIBLE (-3500 3150);
FORCEPROP 1 LAST BODY_TYPE PLUMBING
J 0
(-3500 3200);
DISPLAY 0.872340 (-3500 3200);
PAINT GREEN (-3500 3200);
DISPLAY INVISIBLE (-3500 3200);
FORCEPROP 1 LAST HDL_TAP TRUE
J 0
(-3175 3025);
DISPLAY 0.872340 (-3175 3025);
DISPLAY INVISIBLE (-3175 3025);
FORCEPROP 1 LAST PATH I213
J 0
(-3502 3150);
DISPLAY 0.872340 (-3502 3150);
PAINT GREEN (-3502 3150);
DISPLAY INVISIBLE (-3502 3150);
FORCEADD TAP..1
(-3500 3100);
FORCEPROP 3 LASTPIN (-3550 3100) SIG_NAME M_C_CPU0_SB_DQ<19>
J 0
(-3540 3110);
DISPLAY 0.659574 (-3540 3110);
PAINT MONO (-3540 3110);
DISPLAY INVISIBLE (-3540 3110);
FORCEPROP 1 LASTPIN (-3550 3100) BN 19
J 0
(-3562 3108);
DISPLAY 0.489362 (-3562 3108);
PAINT GREEN (-3562 3108);
FORCEPROP 2 LAST CDS_LIB mstr_standard
J 0
(-3500 3100);
DISPLAY 0.723404 (-3500 3100);
PAINT MONO (-3500 3100);
DISPLAY INVISIBLE (-3500 3100);
FORCEPROP 1 LAST BODY_TYPE PLUMBING
J 0
(-3500 3150);
DISPLAY 0.872340 (-3500 3150);
PAINT GREEN (-3500 3150);
DISPLAY INVISIBLE (-3500 3150);
FORCEPROP 1 LAST HDL_TAP TRUE
J 0
(-3175 2975);
DISPLAY 0.872340 (-3175 2975);
DISPLAY INVISIBLE (-3175 2975);
FORCEPROP 1 LAST PATH I214
J 0
(-3502 3100);
DISPLAY 0.872340 (-3502 3100);
PAINT GREEN (-3502 3100);
DISPLAY INVISIBLE (-3502 3100);
FORCEADD TAP..1
(-3500 2950);
FORCEPROP 3 LASTPIN (-3550 2950) SIG_NAME M_C_CPU0_SB_DQ<22>
J 0
(-3540 2960);
DISPLAY 0.659574 (-3540 2960);
PAINT MONO (-3540 2960);
DISPLAY INVISIBLE (-3540 2960);
FORCEPROP 1 LASTPIN (-3550 2950) BN 22
J 0
(-3562 2958);
DISPLAY 0.489362 (-3562 2958);
PAINT GREEN (-3562 2958);
FORCEPROP 2 LAST CDS_LIB mstr_standard
J 0
(-3500 2950);
DISPLAY 0.723404 (-3500 2950);
PAINT MONO (-3500 2950);
DISPLAY INVISIBLE (-3500 2950);
FORCEPROP 1 LAST BODY_TYPE PLUMBING
J 0
(-3500 3000);
DISPLAY 0.872340 (-3500 3000);
PAINT GREEN (-3500 3000);
DISPLAY INVISIBLE (-3500 3000);
FORCEPROP 1 LAST HDL_TAP TRUE
J 0
(-3175 2825);
DISPLAY 0.872340 (-3175 2825);
DISPLAY INVISIBLE (-3175 2825);
FORCEPROP 1 LAST PATH I215
J 0
(-3502 2950);
DISPLAY 0.872340 (-3502 2950);
PAINT GREEN (-3502 2950);
DISPLAY INVISIBLE (-3502 2950);
FORCEADD TAP..1
(-3500 3050);
FORCEPROP 3 LASTPIN (-3550 3050) SIG_NAME M_C_CPU0_SB_DQ<20>
J 0
(-3540 3060);
DISPLAY 0.659574 (-3540 3060);
PAINT MONO (-3540 3060);
DISPLAY INVISIBLE (-3540 3060);
FORCEPROP 1 LASTPIN (-3550 3050) BN 20
J 0
(-3562 3058);
DISPLAY 0.489362 (-3562 3058);
PAINT GREEN (-3562 3058);
FORCEPROP 2 LAST CDS_LIB mstr_standard
J 0
(-3500 3050);
DISPLAY 0.723404 (-3500 3050);
PAINT MONO (-3500 3050);
DISPLAY INVISIBLE (-3500 3050);
FORCEPROP 1 LAST BODY_TYPE PLUMBING
J 0
(-3500 3100);
DISPLAY 0.872340 (-3500 3100);
PAINT GREEN (-3500 3100);
DISPLAY INVISIBLE (-3500 3100);
FORCEPROP 1 LAST HDL_TAP TRUE
J 0
(-3175 2925);
DISPLAY 0.872340 (-3175 2925);
DISPLAY INVISIBLE (-3175 2925);
FORCEPROP 1 LAST PATH I216
J 0
(-3502 3050);
DISPLAY 0.872340 (-3502 3050);
PAINT GREEN (-3502 3050);
DISPLAY INVISIBLE (-3502 3050);
FORCEADD TAP..1
(-3500 2900);
FORCEPROP 3 LASTPIN (-3550 2900) SIG_NAME M_C_CPU0_SB_DQ<23>
J 0
(-3540 2910);
DISPLAY 0.659574 (-3540 2910);
PAINT MONO (-3540 2910);
DISPLAY INVISIBLE (-3540 2910);
FORCEPROP 1 LASTPIN (-3550 2900) BN 23
J 0
(-3562 2908);
DISPLAY 0.489362 (-3562 2908);
PAINT GREEN (-3562 2908);
FORCEPROP 2 LAST CDS_LIB mstr_standard
J 0
(-3500 2900);
DISPLAY 0.723404 (-3500 2900);
PAINT MONO (-3500 2900);
DISPLAY INVISIBLE (-3500 2900);
FORCEPROP 1 LAST BODY_TYPE PLUMBING
J 0
(-3500 2950);
DISPLAY 0.872340 (-3500 2950);
PAINT GREEN (-3500 2950);
DISPLAY INVISIBLE (-3500 2950);
FORCEPROP 1 LAST HDL_TAP TRUE
J 0
(-3175 2775);
DISPLAY 0.872340 (-3175 2775);
DISPLAY INVISIBLE (-3175 2775);
FORCEPROP 1 LAST PATH I217
J 0
(-3502 2900);
DISPLAY 0.872340 (-3502 2900);
PAINT GREEN (-3502 2900);
DISPLAY INVISIBLE (-3502 2900);
FORCEADD TAP..1
(-3500 3000);
FORCEPROP 3 LASTPIN (-3550 3000) SIG_NAME M_C_CPU0_SB_DQ<21>
J 0
(-3540 3010);
DISPLAY 0.659574 (-3540 3010);
PAINT MONO (-3540 3010);
DISPLAY INVISIBLE (-3540 3010);
FORCEPROP 1 LASTPIN (-3550 3000) BN 21
J 0
(-3562 3008);
DISPLAY 0.489362 (-3562 3008);
PAINT GREEN (-3562 3008);
FORCEPROP 2 LAST CDS_LIB mstr_standard
J 0
(-3500 3000);
DISPLAY 0.723404 (-3500 3000);
PAINT MONO (-3500 3000);
DISPLAY INVISIBLE (-3500 3000);
FORCEPROP 1 LAST BODY_TYPE PLUMBING
J 0
(-3500 3050);
DISPLAY 0.872340 (-3500 3050);
PAINT GREEN (-3500 3050);
DISPLAY INVISIBLE (-3500 3050);
FORCEPROP 1 LAST HDL_TAP TRUE
J 0
(-3175 2875);
DISPLAY 0.872340 (-3175 2875);
DISPLAY INVISIBLE (-3175 2875);
FORCEPROP 1 LAST PATH I218
J 0
(-3502 3000);
DISPLAY 0.872340 (-3502 3000);
PAINT GREEN (-3502 3000);
DISPLAY INVISIBLE (-3502 3000);
FORCEADD TAP..1
(-3500 2800);
FORCEPROP 3 LASTPIN (-3550 2800) SIG_NAME M_C_CPU0_SB_DQ<24>
J 0
(-3540 2810);
DISPLAY 0.659574 (-3540 2810);
PAINT MONO (-3540 2810);
DISPLAY INVISIBLE (-3540 2810);
FORCEPROP 1 LASTPIN (-3550 2800) BN 24
J 0
(-3562 2808);
DISPLAY 0.489362 (-3562 2808);
PAINT GREEN (-3562 2808);
FORCEPROP 2 LAST CDS_LIB mstr_standard
J 0
(-3500 2800);
DISPLAY 0.723404 (-3500 2800);
PAINT MONO (-3500 2800);
DISPLAY INVISIBLE (-3500 2800);
FORCEPROP 1 LAST BODY_TYPE PLUMBING
J 0
(-3500 2850);
DISPLAY 0.872340 (-3500 2850);
PAINT GREEN (-3500 2850);
DISPLAY INVISIBLE (-3500 2850);
FORCEPROP 1 LAST HDL_TAP TRUE
J 0
(-3175 2675);
DISPLAY 0.872340 (-3175 2675);
DISPLAY INVISIBLE (-3175 2675);
FORCEPROP 1 LAST PATH I219
J 0
(-3502 2800);
DISPLAY 0.872340 (-3502 2800);
PAINT GREEN (-3502 2800);
DISPLAY INVISIBLE (-3502 2800);
FORCEADD TAP..1
(-3500 2700);
FORCEPROP 3 LASTPIN (-3550 2700) SIG_NAME M_C_CPU0_SB_DQ<26>
J 0
(-3540 2710);
DISPLAY 0.659574 (-3540 2710);
PAINT MONO (-3540 2710);
DISPLAY INVISIBLE (-3540 2710);
FORCEPROP 1 LASTPIN (-3550 2700) BN 26
J 0
(-3562 2708);
DISPLAY 0.489362 (-3562 2708);
PAINT GREEN (-3562 2708);
FORCEPROP 2 LAST CDS_LIB mstr_standard
J 0
(-3500 2700);
DISPLAY 0.723404 (-3500 2700);
PAINT MONO (-3500 2700);
DISPLAY INVISIBLE (-3500 2700);
FORCEPROP 1 LAST BODY_TYPE PLUMBING
J 0
(-3500 2750);
DISPLAY 0.872340 (-3500 2750);
PAINT GREEN (-3500 2750);
DISPLAY INVISIBLE (-3500 2750);
FORCEPROP 1 LAST HDL_TAP TRUE
J 0
(-3175 2575);
DISPLAY 0.872340 (-3175 2575);
DISPLAY INVISIBLE (-3175 2575);
FORCEPROP 1 LAST PATH I220
J 0
(-3502 2700);
DISPLAY 0.872340 (-3502 2700);
PAINT GREEN (-3502 2700);
DISPLAY INVISIBLE (-3502 2700);
FORCEADD TAP..1
(-3500 2750);
FORCEPROP 3 LASTPIN (-3550 2750) SIG_NAME M_C_CPU0_SB_DQ<25>
J 0
(-3540 2760);
DISPLAY 0.659574 (-3540 2760);
PAINT MONO (-3540 2760);
DISPLAY INVISIBLE (-3540 2760);
FORCEPROP 1 LASTPIN (-3550 2750) BN 25
J 0
(-3562 2758);
DISPLAY 0.489362 (-3562 2758);
PAINT GREEN (-3562 2758);
FORCEPROP 2 LAST CDS_LIB mstr_standard
J 0
(-3500 2750);
DISPLAY 0.723404 (-3500 2750);
PAINT MONO (-3500 2750);
DISPLAY INVISIBLE (-3500 2750);
FORCEPROP 1 LAST BODY_TYPE PLUMBING
J 0
(-3500 2800);
DISPLAY 0.872340 (-3500 2800);
PAINT GREEN (-3500 2800);
DISPLAY INVISIBLE (-3500 2800);
FORCEPROP 1 LAST HDL_TAP TRUE
J 0
(-3175 2625);
DISPLAY 0.872340 (-3175 2625);
DISPLAY INVISIBLE (-3175 2625);
FORCEPROP 1 LAST PATH I221
J 0
(-3502 2750);
DISPLAY 0.872340 (-3502 2750);
PAINT GREEN (-3502 2750);
DISPLAY INVISIBLE (-3502 2750);
FORCEADD TAP..1
(-3500 2650);
FORCEPROP 3 LASTPIN (-3550 2650) SIG_NAME M_C_CPU0_SB_DQ<27>
J 0
(-3540 2660);
DISPLAY 0.659574 (-3540 2660);
PAINT MONO (-3540 2660);
DISPLAY INVISIBLE (-3540 2660);
FORCEPROP 1 LASTPIN (-3550 2650) BN 27
J 0
(-3562 2658);
DISPLAY 0.489362 (-3562 2658);
PAINT GREEN (-3562 2658);
FORCEPROP 2 LAST CDS_LIB mstr_standard
J 0
(-3500 2650);
DISPLAY 0.723404 (-3500 2650);
PAINT MONO (-3500 2650);
DISPLAY INVISIBLE (-3500 2650);
FORCEPROP 1 LAST BODY_TYPE PLUMBING
J 0
(-3500 2700);
DISPLAY 0.872340 (-3500 2700);
PAINT GREEN (-3500 2700);
DISPLAY INVISIBLE (-3500 2700);
FORCEPROP 1 LAST HDL_TAP TRUE
J 0
(-3175 2525);
DISPLAY 0.872340 (-3175 2525);
DISPLAY INVISIBLE (-3175 2525);
FORCEPROP 1 LAST PATH I222
J 0
(-3502 2650);
DISPLAY 0.872340 (-3502 2650);
PAINT GREEN (-3502 2650);
DISPLAY INVISIBLE (-3502 2650);
FORCEADD TAP..1
(-3500 2600);
FORCEPROP 3 LASTPIN (-3550 2600) SIG_NAME M_C_CPU0_SB_DQ<28>
J 0
(-3540 2610);
DISPLAY 0.659574 (-3540 2610);
PAINT MONO (-3540 2610);
DISPLAY INVISIBLE (-3540 2610);
FORCEPROP 1 LASTPIN (-3550 2600) BN 28
J 0
(-3562 2608);
DISPLAY 0.489362 (-3562 2608);
PAINT GREEN (-3562 2608);
FORCEPROP 2 LAST CDS_LIB mstr_standard
J 0
(-3500 2600);
DISPLAY 0.723404 (-3500 2600);
PAINT MONO (-3500 2600);
DISPLAY INVISIBLE (-3500 2600);
FORCEPROP 1 LAST BODY_TYPE PLUMBING
J 0
(-3500 2650);
DISPLAY 0.872340 (-3500 2650);
PAINT GREEN (-3500 2650);
DISPLAY INVISIBLE (-3500 2650);
FORCEPROP 1 LAST HDL_TAP TRUE
J 0
(-3175 2475);
DISPLAY 0.872340 (-3175 2475);
DISPLAY INVISIBLE (-3175 2475);
FORCEPROP 1 LAST PATH I223
J 0
(-3502 2600);
DISPLAY 0.872340 (-3502 2600);
PAINT GREEN (-3502 2600);
DISPLAY INVISIBLE (-3502 2600);
FORCEADD TAP..1
(-3500 2550);
FORCEPROP 3 LASTPIN (-3550 2550) SIG_NAME M_C_CPU0_SB_DQ<29>
J 0
(-3540 2560);
DISPLAY 0.659574 (-3540 2560);
PAINT MONO (-3540 2560);
DISPLAY INVISIBLE (-3540 2560);
FORCEPROP 1 LASTPIN (-3550 2550) BN 29
J 0
(-3562 2558);
DISPLAY 0.489362 (-3562 2558);
PAINT GREEN (-3562 2558);
FORCEPROP 2 LAST CDS_LIB mstr_standard
J 0
(-3500 2550);
DISPLAY 0.723404 (-3500 2550);
PAINT MONO (-3500 2550);
DISPLAY INVISIBLE (-3500 2550);
FORCEPROP 1 LAST BODY_TYPE PLUMBING
J 0
(-3500 2600);
DISPLAY 0.872340 (-3500 2600);
PAINT GREEN (-3500 2600);
DISPLAY INVISIBLE (-3500 2600);
FORCEPROP 1 LAST HDL_TAP TRUE
J 0
(-3175 2425);
DISPLAY 0.872340 (-3175 2425);
DISPLAY INVISIBLE (-3175 2425);
FORCEPROP 1 LAST PATH I224
J 0
(-3502 2550);
DISPLAY 0.872340 (-3502 2550);
PAINT GREEN (-3502 2550);
DISPLAY INVISIBLE (-3502 2550);
FORCEADD TAP..1
(-3500 2500);
FORCEPROP 3 LASTPIN (-3550 2500) SIG_NAME M_C_CPU0_SB_DQ<30>
J 0
(-3540 2510);
DISPLAY 0.659574 (-3540 2510);
PAINT MONO (-3540 2510);
DISPLAY INVISIBLE (-3540 2510);
FORCEPROP 1 LASTPIN (-3550 2500) BN 30
J 0
(-3562 2508);
DISPLAY 0.489362 (-3562 2508);
PAINT GREEN (-3562 2508);
FORCEPROP 2 LAST CDS_LIB mstr_standard
J 0
(-3500 2500);
DISPLAY 0.723404 (-3500 2500);
PAINT MONO (-3500 2500);
DISPLAY INVISIBLE (-3500 2500);
FORCEPROP 1 LAST BODY_TYPE PLUMBING
J 0
(-3500 2550);
DISPLAY 0.872340 (-3500 2550);
PAINT GREEN (-3500 2550);
DISPLAY INVISIBLE (-3500 2550);
FORCEPROP 1 LAST HDL_TAP TRUE
J 0
(-3175 2375);
DISPLAY 0.872340 (-3175 2375);
DISPLAY INVISIBLE (-3175 2375);
FORCEPROP 1 LAST PATH I225
J 0
(-3502 2500);
DISPLAY 0.872340 (-3502 2500);
PAINT GREEN (-3502 2500);
DISPLAY INVISIBLE (-3502 2500);
FORCEADD TAP..1
(-3500 2450);
FORCEPROP 3 LASTPIN (-3550 2450) SIG_NAME M_C_CPU0_SB_DQ<31>
J 0
(-3540 2460);
DISPLAY 0.659574 (-3540 2460);
PAINT MONO (-3540 2460);
DISPLAY INVISIBLE (-3540 2460);
FORCEPROP 1 LASTPIN (-3550 2450) BN 31
J 0
(-3562 2458);
DISPLAY 0.489362 (-3562 2458);
PAINT GREEN (-3562 2458);
FORCEPROP 2 LAST CDS_LIB mstr_standard
J 0
(-3500 2450);
DISPLAY 0.723404 (-3500 2450);
PAINT MONO (-3500 2450);
DISPLAY INVISIBLE (-3500 2450);
FORCEPROP 1 LAST BODY_TYPE PLUMBING
J 0
(-3500 2500);
DISPLAY 0.872340 (-3500 2500);
PAINT GREEN (-3500 2500);
DISPLAY INVISIBLE (-3500 2500);
FORCEPROP 1 LAST HDL_TAP TRUE
J 0
(-3175 2325);
DISPLAY 0.872340 (-3175 2325);
DISPLAY INVISIBLE (-3175 2325);
FORCEPROP 1 LAST PATH I226
J 0
(-3502 2450);
DISPLAY 0.872340 (-3502 2450);
PAINT GREEN (-3502 2450);
DISPLAY INVISIBLE (-3502 2450);
FORCEADD TAP..1
(-3500 2350);
FORCEPROP 3 LASTPIN (-3550 2350) SIG_NAME M_C_CPU0_SA_CB<0>
J 0
(-3540 2360);
DISPLAY 0.659574 (-3540 2360);
PAINT MONO (-3540 2360);
DISPLAY INVISIBLE (-3540 2360);
FORCEPROP 1 LASTPIN (-3550 2350) BN 0
J 0
(-3562 2358);
DISPLAY 0.489362 (-3562 2358);
PAINT GREEN (-3562 2358);
FORCEPROP 2 LAST CDS_LIB mstr_standard
J 2
(-3500 2350);
DISPLAY 0.723404 (-3500 2350);
PAINT MONO (-3500 2350);
DISPLAY INVISIBLE (-3500 2350);
FORCEPROP 1 LAST BODY_TYPE PLUMBING
J 0
(-3500 2400);
DISPLAY 0.872340 (-3500 2400);
PAINT GREEN (-3500 2400);
DISPLAY INVISIBLE (-3500 2400);
FORCEPROP 1 LAST HDL_TAP TRUE
J 0
(-3175 2225);
DISPLAY 0.872340 (-3175 2225);
DISPLAY INVISIBLE (-3175 2225);
FORCEPROP 1 LAST PATH I227
J 0
(-3502 2350);
DISPLAY 0.872340 (-3502 2350);
PAINT GREEN (-3502 2350);
DISPLAY INVISIBLE (-3502 2350);
FORCEADD TAP..1
(-3500 2300);
FORCEPROP 3 LASTPIN (-3550 2300) SIG_NAME M_C_CPU0_SA_CB<1>
J 0
(-3540 2310);
DISPLAY 0.659574 (-3540 2310);
PAINT MONO (-3540 2310);
DISPLAY INVISIBLE (-3540 2310);
FORCEPROP 1 LASTPIN (-3550 2300) BN 1
J 0
(-3562 2308);
DISPLAY 0.489362 (-3562 2308);
PAINT GREEN (-3562 2308);
FORCEPROP 2 LAST CDS_LIB mstr_standard
J 2
(-3500 2300);
DISPLAY 0.723404 (-3500 2300);
PAINT MONO (-3500 2300);
DISPLAY INVISIBLE (-3500 2300);
FORCEPROP 1 LAST BODY_TYPE PLUMBING
J 0
(-3500 2350);
DISPLAY 0.872340 (-3500 2350);
PAINT GREEN (-3500 2350);
DISPLAY INVISIBLE (-3500 2350);
FORCEPROP 1 LAST HDL_TAP TRUE
J 0
(-3175 2175);
DISPLAY 0.872340 (-3175 2175);
DISPLAY INVISIBLE (-3175 2175);
FORCEPROP 1 LAST PATH I228
J 0
(-3502 2300);
DISPLAY 0.872340 (-3502 2300);
PAINT GREEN (-3502 2300);
DISPLAY INVISIBLE (-3502 2300);
FORCEADD TAP..1
(-3500 2250);
FORCEPROP 3 LASTPIN (-3550 2250) SIG_NAME M_C_CPU0_SA_CB<2>
J 0
(-3540 2260);
DISPLAY 0.659574 (-3540 2260);
PAINT MONO (-3540 2260);
DISPLAY INVISIBLE (-3540 2260);
FORCEPROP 1 LASTPIN (-3550 2250) BN 2
J 0
(-3562 2258);
DISPLAY 0.489362 (-3562 2258);
PAINT GREEN (-3562 2258);
FORCEPROP 2 LAST CDS_LIB mstr_standard
J 2
(-3500 2250);
DISPLAY 0.723404 (-3500 2250);
PAINT MONO (-3500 2250);
DISPLAY INVISIBLE (-3500 2250);
FORCEPROP 1 LAST BODY_TYPE PLUMBING
J 0
(-3500 2300);
DISPLAY 0.872340 (-3500 2300);
PAINT GREEN (-3500 2300);
DISPLAY INVISIBLE (-3500 2300);
FORCEPROP 1 LAST HDL_TAP TRUE
J 0
(-3175 2125);
DISPLAY 0.872340 (-3175 2125);
DISPLAY INVISIBLE (-3175 2125);
FORCEPROP 1 LAST PATH I229
J 0
(-3502 2250);
DISPLAY 0.872340 (-3502 2250);
PAINT GREEN (-3502 2250);
DISPLAY INVISIBLE (-3502 2250);
FORCEADD TAP..1
(-3500 2200);
FORCEPROP 3 LASTPIN (-3550 2200) SIG_NAME M_C_CPU0_SA_CB<3>
J 0
(-3540 2210);
DISPLAY 0.659574 (-3540 2210);
PAINT MONO (-3540 2210);
DISPLAY INVISIBLE (-3540 2210);
FORCEPROP 1 LASTPIN (-3550 2200) BN 3
J 0
(-3562 2208);
DISPLAY 0.489362 (-3562 2208);
PAINT GREEN (-3562 2208);
FORCEPROP 2 LAST CDS_LIB mstr_standard
J 2
(-3500 2200);
DISPLAY 0.723404 (-3500 2200);
PAINT MONO (-3500 2200);
DISPLAY INVISIBLE (-3500 2200);
FORCEPROP 1 LAST BODY_TYPE PLUMBING
J 0
(-3500 2250);
DISPLAY 0.872340 (-3500 2250);
PAINT GREEN (-3500 2250);
DISPLAY INVISIBLE (-3500 2250);
FORCEPROP 1 LAST HDL_TAP TRUE
J 0
(-3175 2075);
DISPLAY 0.872340 (-3175 2075);
DISPLAY INVISIBLE (-3175 2075);
FORCEPROP 1 LAST PATH I230
J 0
(-3502 2200);
DISPLAY 0.872340 (-3502 2200);
PAINT GREEN (-3502 2200);
DISPLAY INVISIBLE (-3502 2200);
FORCEADD TAP..1
(-3500 2150);
FORCEPROP 3 LASTPIN (-3550 2150) SIG_NAME M_C_CPU0_SA_CB<4>
J 0
(-3540 2160);
DISPLAY 0.659574 (-3540 2160);
PAINT MONO (-3540 2160);
DISPLAY INVISIBLE (-3540 2160);
FORCEPROP 1 LASTPIN (-3550 2150) BN 4
J 0
(-3562 2158);
DISPLAY 0.489362 (-3562 2158);
PAINT GREEN (-3562 2158);
FORCEPROP 2 LAST CDS_LIB mstr_standard
J 2
(-3500 2150);
DISPLAY 0.723404 (-3500 2150);
PAINT MONO (-3500 2150);
DISPLAY INVISIBLE (-3500 2150);
FORCEPROP 1 LAST BODY_TYPE PLUMBING
J 0
(-3500 2200);
DISPLAY 0.872340 (-3500 2200);
PAINT GREEN (-3500 2200);
DISPLAY INVISIBLE (-3500 2200);
FORCEPROP 1 LAST HDL_TAP TRUE
J 0
(-3175 2025);
DISPLAY 0.872340 (-3175 2025);
DISPLAY INVISIBLE (-3175 2025);
FORCEPROP 1 LAST PATH I231
J 0
(-3502 2150);
DISPLAY 0.872340 (-3502 2150);
PAINT GREEN (-3502 2150);
DISPLAY INVISIBLE (-3502 2150);
FORCEADD TAP..1
(-3500 2100);
FORCEPROP 3 LASTPIN (-3550 2100) SIG_NAME M_C_CPU0_SA_CB<5>
J 0
(-3540 2110);
DISPLAY 0.659574 (-3540 2110);
PAINT MONO (-3540 2110);
DISPLAY INVISIBLE (-3540 2110);
FORCEPROP 1 LASTPIN (-3550 2100) BN 5
J 0
(-3562 2108);
DISPLAY 0.489362 (-3562 2108);
PAINT GREEN (-3562 2108);
FORCEPROP 2 LAST CDS_LIB mstr_standard
J 2
(-3500 2100);
DISPLAY 0.723404 (-3500 2100);
PAINT MONO (-3500 2100);
DISPLAY INVISIBLE (-3500 2100);
FORCEPROP 1 LAST BODY_TYPE PLUMBING
J 0
(-3500 2150);
DISPLAY 0.872340 (-3500 2150);
PAINT GREEN (-3500 2150);
DISPLAY INVISIBLE (-3500 2150);
FORCEPROP 1 LAST HDL_TAP TRUE
J 0
(-3175 1975);
DISPLAY 0.872340 (-3175 1975);
DISPLAY INVISIBLE (-3175 1975);
FORCEPROP 1 LAST PATH I232
J 0
(-3502 2100);
DISPLAY 0.872340 (-3502 2100);
PAINT GREEN (-3502 2100);
DISPLAY INVISIBLE (-3502 2100);
FORCEADD TAP..1
(-3500 2050);
FORCEPROP 3 LASTPIN (-3550 2050) SIG_NAME M_C_CPU0_SA_CB<6>
J 0
(-3540 2060);
DISPLAY 0.659574 (-3540 2060);
PAINT MONO (-3540 2060);
DISPLAY INVISIBLE (-3540 2060);
FORCEPROP 1 LASTPIN (-3550 2050) BN 6
J 0
(-3562 2058);
DISPLAY 0.489362 (-3562 2058);
PAINT GREEN (-3562 2058);
FORCEPROP 2 LAST CDS_LIB mstr_standard
J 2
(-3500 2050);
DISPLAY 0.723404 (-3500 2050);
PAINT MONO (-3500 2050);
DISPLAY INVISIBLE (-3500 2050);
FORCEPROP 1 LAST BODY_TYPE PLUMBING
J 0
(-3500 2100);
DISPLAY 0.872340 (-3500 2100);
PAINT GREEN (-3500 2100);
DISPLAY INVISIBLE (-3500 2100);
FORCEPROP 1 LAST HDL_TAP TRUE
J 0
(-3175 1925);
DISPLAY 0.872340 (-3175 1925);
DISPLAY INVISIBLE (-3175 1925);
FORCEPROP 1 LAST PATH I233
J 0
(-3502 2050);
DISPLAY 0.872340 (-3502 2050);
PAINT GREEN (-3502 2050);
DISPLAY INVISIBLE (-3502 2050);
FORCEADD OFFPAGE..6
R 2
(-2900 1950);
FORCEPROP 2 LAST $XR0 88 
J 0
(-2686 1950);
DISPLAY 0.638298 (-2686 1950);
PAINT MONO (-2686 1950);
FORCEPROP 2 LAST CDS_LIB mstr_standard
J 2
(-2900 1950);
DISPLAY 0.723404 (-2900 1950);
PAINT MONO (-2900 1950);
DISPLAY INVISIBLE (-2900 1950);
FORCEPROP 1 LAST OFFPAGE TRUE
J 2
(-3225 1825);
DISPLAY 0.872340 (-3225 1825);
PAINT GREEN (-3225 1825);
DISPLAY INVISIBLE (-3225 1825);
FORCEPROP 1 LAST COMMENT_BODY TRUE
J 2
(-3000 1875);
DISPLAY 0.872340 (-3000 1875);
PAINT GREEN (-3000 1875);
DISPLAY INVISIBLE (-3000 1875);
FORCEPROP 2 LAST PATH I234
J 0
(-2675 2000);
DISPLAY 1.021277 (-2675 2000);
DISPLAY INVISIBLE (-2675 2000);
FORCEADD TAP..1
(-3500 2000);
FORCEPROP 3 LASTPIN (-3550 2000) SIG_NAME M_C_CPU0_SA_CB<7>
J 0
(-3540 2010);
DISPLAY 0.659574 (-3540 2010);
PAINT MONO (-3540 2010);
DISPLAY INVISIBLE (-3540 2010);
FORCEPROP 1 LASTPIN (-3550 2000) BN 7
J 0
(-3562 2008);
DISPLAY 0.489362 (-3562 2008);
PAINT GREEN (-3562 2008);
FORCEPROP 2 LAST CDS_LIB mstr_standard
J 2
(-3500 2000);
DISPLAY 0.723404 (-3500 2000);
PAINT MONO (-3500 2000);
DISPLAY INVISIBLE (-3500 2000);
FORCEPROP 1 LAST BODY_TYPE PLUMBING
J 0
(-3500 2050);
DISPLAY 0.872340 (-3500 2050);
PAINT GREEN (-3500 2050);
DISPLAY INVISIBLE (-3500 2050);
FORCEPROP 1 LAST HDL_TAP TRUE
J 0
(-3175 1875);
DISPLAY 0.872340 (-3175 1875);
DISPLAY INVISIBLE (-3175 1875);
FORCEPROP 1 LAST PATH I235
J 0
(-3502 2000);
DISPLAY 0.872340 (-3502 2000);
PAINT GREEN (-3502 2000);
DISPLAY INVISIBLE (-3502 2000);
FORCEADD TAP..1
(-3500 1900);
FORCEPROP 3 LASTPIN (-3550 1900) SIG_NAME M_C_CPU0_SB_CB<0>
J 0
(-3540 1910);
DISPLAY 0.659574 (-3540 1910);
PAINT MONO (-3540 1910);
DISPLAY INVISIBLE (-3540 1910);
FORCEPROP 1 LASTPIN (-3550 1900) BN 0
J 0
(-3562 1908);
DISPLAY 0.489362 (-3562 1908);
PAINT GREEN (-3562 1908);
FORCEPROP 2 LAST CDS_LIB mstr_standard
J 2
(-3500 1900);
DISPLAY 0.723404 (-3500 1900);
PAINT MONO (-3500 1900);
DISPLAY INVISIBLE (-3500 1900);
FORCEPROP 1 LAST BODY_TYPE PLUMBING
J 0
(-3500 1950);
DISPLAY 0.872340 (-3500 1950);
PAINT GREEN (-3500 1950);
DISPLAY INVISIBLE (-3500 1950);
FORCEPROP 1 LAST HDL_TAP TRUE
J 0
(-3175 1775);
DISPLAY 0.872340 (-3175 1775);
DISPLAY INVISIBLE (-3175 1775);
FORCEPROP 1 LAST PATH I236
J 0
(-3502 1900);
DISPLAY 0.872340 (-3502 1900);
PAINT GREEN (-3502 1900);
DISPLAY INVISIBLE (-3502 1900);
FORCEADD TAP..1
(-3500 1850);
FORCEPROP 3 LASTPIN (-3550 1850) SIG_NAME M_C_CPU0_SB_CB<1>
J 0
(-3540 1860);
DISPLAY 0.659574 (-3540 1860);
PAINT MONO (-3540 1860);
DISPLAY INVISIBLE (-3540 1860);
FORCEPROP 1 LASTPIN (-3550 1850) BN 1
J 0
(-3562 1858);
DISPLAY 0.489362 (-3562 1858);
PAINT GREEN (-3562 1858);
FORCEPROP 2 LAST CDS_LIB mstr_standard
J 2
(-3500 1850);
DISPLAY 0.723404 (-3500 1850);
PAINT MONO (-3500 1850);
DISPLAY INVISIBLE (-3500 1850);
FORCEPROP 1 LAST BODY_TYPE PLUMBING
J 0
(-3500 1900);
DISPLAY 0.872340 (-3500 1900);
PAINT GREEN (-3500 1900);
DISPLAY INVISIBLE (-3500 1900);
FORCEPROP 1 LAST HDL_TAP TRUE
J 0
(-3175 1725);
DISPLAY 0.872340 (-3175 1725);
DISPLAY INVISIBLE (-3175 1725);
FORCEPROP 1 LAST PATH I237
J 0
(-3502 1850);
DISPLAY 0.872340 (-3502 1850);
PAINT GREEN (-3502 1850);
DISPLAY INVISIBLE (-3502 1850);
FORCEADD TAP..1
(-3500 1800);
FORCEPROP 3 LASTPIN (-3550 1800) SIG_NAME M_C_CPU0_SB_CB<2>
J 0
(-3540 1810);
DISPLAY 0.659574 (-3540 1810);
PAINT MONO (-3540 1810);
DISPLAY INVISIBLE (-3540 1810);
FORCEPROP 1 LASTPIN (-3550 1800) BN 2
J 0
(-3562 1808);
DISPLAY 0.489362 (-3562 1808);
PAINT GREEN (-3562 1808);
FORCEPROP 2 LAST CDS_LIB mstr_standard
J 2
(-3500 1800);
DISPLAY 0.723404 (-3500 1800);
PAINT MONO (-3500 1800);
DISPLAY INVISIBLE (-3500 1800);
FORCEPROP 1 LAST BODY_TYPE PLUMBING
J 0
(-3500 1850);
DISPLAY 0.872340 (-3500 1850);
PAINT GREEN (-3500 1850);
DISPLAY INVISIBLE (-3500 1850);
FORCEPROP 1 LAST HDL_TAP TRUE
J 0
(-3175 1675);
DISPLAY 0.872340 (-3175 1675);
DISPLAY INVISIBLE (-3175 1675);
FORCEPROP 1 LAST PATH I238
J 0
(-3502 1800);
DISPLAY 0.872340 (-3502 1800);
PAINT GREEN (-3502 1800);
DISPLAY INVISIBLE (-3502 1800);
FORCEADD TAP..1
(-3500 1750);
FORCEPROP 3 LASTPIN (-3550 1750) SIG_NAME M_C_CPU0_SB_CB<3>
J 0
(-3540 1760);
DISPLAY 0.659574 (-3540 1760);
PAINT MONO (-3540 1760);
DISPLAY INVISIBLE (-3540 1760);
FORCEPROP 1 LASTPIN (-3550 1750) BN 3
J 0
(-3562 1758);
DISPLAY 0.489362 (-3562 1758);
PAINT GREEN (-3562 1758);
FORCEPROP 2 LAST CDS_LIB mstr_standard
J 2
(-3500 1750);
DISPLAY 0.723404 (-3500 1750);
PAINT MONO (-3500 1750);
DISPLAY INVISIBLE (-3500 1750);
FORCEPROP 1 LAST BODY_TYPE PLUMBING
J 0
(-3500 1800);
DISPLAY 0.872340 (-3500 1800);
PAINT GREEN (-3500 1800);
DISPLAY INVISIBLE (-3500 1800);
FORCEPROP 1 LAST HDL_TAP TRUE
J 0
(-3175 1625);
DISPLAY 0.872340 (-3175 1625);
DISPLAY INVISIBLE (-3175 1625);
FORCEPROP 1 LAST PATH I239
J 0
(-3502 1750);
DISPLAY 0.872340 (-3502 1750);
PAINT GREEN (-3502 1750);
DISPLAY INVISIBLE (-3502 1750);
FORCEADD TAP..1
(-3500 1700);
FORCEPROP 3 LASTPIN (-3550 1700) SIG_NAME M_C_CPU0_SB_CB<4>
J 0
(-3540 1710);
DISPLAY 0.659574 (-3540 1710);
PAINT MONO (-3540 1710);
DISPLAY INVISIBLE (-3540 1710);
FORCEPROP 1 LASTPIN (-3550 1700) BN 4
J 0
(-3562 1708);
DISPLAY 0.489362 (-3562 1708);
PAINT GREEN (-3562 1708);
FORCEPROP 2 LAST CDS_LIB mstr_standard
J 2
(-3500 1700);
DISPLAY 0.723404 (-3500 1700);
PAINT MONO (-3500 1700);
DISPLAY INVISIBLE (-3500 1700);
FORCEPROP 1 LAST BODY_TYPE PLUMBING
J 0
(-3500 1750);
DISPLAY 0.872340 (-3500 1750);
PAINT GREEN (-3500 1750);
DISPLAY INVISIBLE (-3500 1750);
FORCEPROP 1 LAST HDL_TAP TRUE
J 0
(-3175 1575);
DISPLAY 0.872340 (-3175 1575);
DISPLAY INVISIBLE (-3175 1575);
FORCEPROP 1 LAST PATH I240
J 0
(-3502 1700);
DISPLAY 0.872340 (-3502 1700);
PAINT GREEN (-3502 1700);
DISPLAY INVISIBLE (-3502 1700);
FORCEADD TAP..1
(-3500 1650);
FORCEPROP 3 LASTPIN (-3550 1650) SIG_NAME M_C_CPU0_SB_CB<5>
J 0
(-3540 1660);
DISPLAY 0.659574 (-3540 1660);
PAINT MONO (-3540 1660);
DISPLAY INVISIBLE (-3540 1660);
FORCEPROP 1 LASTPIN (-3550 1650) BN 5
J 0
(-3562 1658);
DISPLAY 0.489362 (-3562 1658);
PAINT GREEN (-3562 1658);
FORCEPROP 2 LAST CDS_LIB mstr_standard
J 2
(-3500 1650);
DISPLAY 0.723404 (-3500 1650);
PAINT MONO (-3500 1650);
DISPLAY INVISIBLE (-3500 1650);
FORCEPROP 1 LAST BODY_TYPE PLUMBING
J 0
(-3500 1700);
DISPLAY 0.872340 (-3500 1700);
PAINT GREEN (-3500 1700);
DISPLAY INVISIBLE (-3500 1700);
FORCEPROP 1 LAST HDL_TAP TRUE
J 0
(-3175 1525);
DISPLAY 0.872340 (-3175 1525);
DISPLAY INVISIBLE (-3175 1525);
FORCEPROP 1 LAST PATH I241
J 0
(-3502 1650);
DISPLAY 0.872340 (-3502 1650);
PAINT GREEN (-3502 1650);
DISPLAY INVISIBLE (-3502 1650);
FORCEADD TAP..1
(-3500 1550);
FORCEPROP 3 LASTPIN (-3550 1550) SIG_NAME M_C_CPU0_SB_CB<7>
J 0
(-3540 1560);
DISPLAY 0.659574 (-3540 1560);
PAINT MONO (-3540 1560);
DISPLAY INVISIBLE (-3540 1560);
FORCEPROP 1 LASTPIN (-3550 1550) BN 7
J 0
(-3562 1558);
DISPLAY 0.489362 (-3562 1558);
PAINT GREEN (-3562 1558);
FORCEPROP 2 LAST CDS_LIB mstr_standard
J 2
(-3500 1550);
DISPLAY 0.723404 (-3500 1550);
PAINT MONO (-3500 1550);
DISPLAY INVISIBLE (-3500 1550);
FORCEPROP 1 LAST BODY_TYPE PLUMBING
J 0
(-3500 1600);
DISPLAY 0.872340 (-3500 1600);
PAINT GREEN (-3500 1600);
DISPLAY INVISIBLE (-3500 1600);
FORCEPROP 1 LAST HDL_TAP TRUE
J 0
(-3175 1425);
DISPLAY 0.872340 (-3175 1425);
DISPLAY INVISIBLE (-3175 1425);
FORCEPROP 1 LAST PATH I242
J 0
(-3502 1550);
DISPLAY 0.872340 (-3502 1550);
PAINT GREEN (-3502 1550);
DISPLAY INVISIBLE (-3502 1550);
FORCEADD TAP..1
(-3500 1600);
FORCEPROP 3 LASTPIN (-3550 1600) SIG_NAME M_C_CPU0_SB_CB<6>
J 0
(-3540 1610);
DISPLAY 0.659574 (-3540 1610);
PAINT MONO (-3540 1610);
DISPLAY INVISIBLE (-3540 1610);
FORCEPROP 1 LASTPIN (-3550 1600) BN 6
J 0
(-3562 1608);
DISPLAY 0.489362 (-3562 1608);
PAINT GREEN (-3562 1608);
FORCEPROP 2 LAST CDS_LIB mstr_standard
J 2
(-3500 1600);
DISPLAY 0.723404 (-3500 1600);
PAINT MONO (-3500 1600);
DISPLAY INVISIBLE (-3500 1600);
FORCEPROP 1 LAST BODY_TYPE PLUMBING
J 0
(-3500 1650);
DISPLAY 0.872340 (-3500 1650);
PAINT GREEN (-3500 1650);
DISPLAY INVISIBLE (-3500 1650);
FORCEPROP 1 LAST HDL_TAP TRUE
J 0
(-3175 1475);
DISPLAY 0.872340 (-3175 1475);
DISPLAY INVISIBLE (-3175 1475);
FORCEPROP 1 LAST PATH I243
J 0
(-3502 1600);
DISPLAY 0.872340 (-3502 1600);
PAINT GREEN (-3502 1600);
DISPLAY INVISIBLE (-3502 1600);
FORCEADD TAP..1
R 2
(-5925 5950);
FORCEPROP 3 LASTPIN (-5875 5950) SIG_NAME M_C_CPU0_SA_DQS_DP<0>
J 0
(-5865 5960);
DISPLAY 0.659574 (-5865 5960);
PAINT MONO (-5865 5960);
DISPLAY INVISIBLE (-5865 5960);
FORCEPROP 1 LASTPIN (-5875 5950) BN 0
J 2
(-5863 5958);
DISPLAY 0.489362 (-5863 5958);
PAINT GREEN (-5863 5958);
FORCEPROP 2 LAST CDS_LIB mstr_standard
J 2
(-5925 5950);
DISPLAY 0.723404 (-5925 5950);
PAINT MONO (-5925 5950);
DISPLAY INVISIBLE (-5925 5950);
FORCEPROP 1 LAST BODY_TYPE PLUMBING
J 2
(-5925 6000);
DISPLAY 0.872340 (-5925 6000);
PAINT GREEN (-5925 6000);
DISPLAY INVISIBLE (-5925 6000);
FORCEPROP 1 LAST HDL_TAP TRUE
J 2
(-6250 5825);
DISPLAY 0.872340 (-6250 5825);
DISPLAY INVISIBLE (-6250 5825);
FORCEPROP 1 LAST PATH I244
J 2
(-5923 5950);
DISPLAY 0.872340 (-5923 5950);
PAINT GREEN (-5923 5950);
DISPLAY INVISIBLE (-5923 5950);
FORCEADD TAP..1
R 2
(-5925 5850);
FORCEPROP 3 LASTPIN (-5875 5850) SIG_NAME M_C_CPU0_SA_DQS_DP<1>
J 0
(-5865 5860);
DISPLAY 0.659574 (-5865 5860);
PAINT MONO (-5865 5860);
DISPLAY INVISIBLE (-5865 5860);
FORCEPROP 1 LASTPIN (-5875 5850) BN 1
J 2
(-5863 5858);
DISPLAY 0.489362 (-5863 5858);
PAINT GREEN (-5863 5858);
FORCEPROP 2 LAST CDS_LIB mstr_standard
J 2
(-5925 5850);
DISPLAY 0.723404 (-5925 5850);
PAINT MONO (-5925 5850);
DISPLAY INVISIBLE (-5925 5850);
FORCEPROP 1 LAST BODY_TYPE PLUMBING
J 2
(-5925 5900);
DISPLAY 0.872340 (-5925 5900);
PAINT GREEN (-5925 5900);
DISPLAY INVISIBLE (-5925 5900);
FORCEPROP 1 LAST HDL_TAP TRUE
J 2
(-6250 5725);
DISPLAY 0.872340 (-6250 5725);
DISPLAY INVISIBLE (-6250 5725);
FORCEPROP 1 LAST PATH I245
J 2
(-5923 5850);
DISPLAY 0.872340 (-5923 5850);
PAINT GREEN (-5923 5850);
DISPLAY INVISIBLE (-5923 5850);
FORCEADD TAP..1
R 2
(-5925 5750);
FORCEPROP 3 LASTPIN (-5875 5750) SIG_NAME M_C_CPU0_SA_DQS_DP<2>
J 0
(-5865 5760);
DISPLAY 0.659574 (-5865 5760);
PAINT MONO (-5865 5760);
DISPLAY INVISIBLE (-5865 5760);
FORCEPROP 1 LASTPIN (-5875 5750) BN 2
J 2
(-5863 5758);
DISPLAY 0.489362 (-5863 5758);
PAINT GREEN (-5863 5758);
FORCEPROP 2 LAST CDS_LIB mstr_standard
J 2
(-5925 5750);
DISPLAY 0.723404 (-5925 5750);
PAINT MONO (-5925 5750);
DISPLAY INVISIBLE (-5925 5750);
FORCEPROP 1 LAST BODY_TYPE PLUMBING
J 2
(-5925 5800);
DISPLAY 0.872340 (-5925 5800);
PAINT GREEN (-5925 5800);
DISPLAY INVISIBLE (-5925 5800);
FORCEPROP 1 LAST HDL_TAP TRUE
J 2
(-6250 5625);
DISPLAY 0.872340 (-6250 5625);
DISPLAY INVISIBLE (-6250 5625);
FORCEPROP 1 LAST PATH I246
J 2
(-5923 5750);
DISPLAY 0.872340 (-5923 5750);
PAINT GREEN (-5923 5750);
DISPLAY INVISIBLE (-5923 5750);
FORCEADD TAP..1
R 2
(-5925 5650);
FORCEPROP 3 LASTPIN (-5875 5650) SIG_NAME M_C_CPU0_SA_DQS_DP<3>
J 0
(-5865 5660);
DISPLAY 0.659574 (-5865 5660);
PAINT MONO (-5865 5660);
DISPLAY INVISIBLE (-5865 5660);
FORCEPROP 1 LASTPIN (-5875 5650) BN 3
J 2
(-5863 5658);
DISPLAY 0.489362 (-5863 5658);
PAINT GREEN (-5863 5658);
FORCEPROP 2 LAST CDS_LIB mstr_standard
J 2
(-5925 5650);
DISPLAY 0.723404 (-5925 5650);
PAINT MONO (-5925 5650);
DISPLAY INVISIBLE (-5925 5650);
FORCEPROP 1 LAST BODY_TYPE PLUMBING
J 2
(-5925 5700);
DISPLAY 0.872340 (-5925 5700);
PAINT GREEN (-5925 5700);
DISPLAY INVISIBLE (-5925 5700);
FORCEPROP 1 LAST HDL_TAP TRUE
J 2
(-6250 5525);
DISPLAY 0.872340 (-6250 5525);
DISPLAY INVISIBLE (-6250 5525);
FORCEPROP 1 LAST PATH I247
J 2
(-5923 5650);
DISPLAY 0.872340 (-5923 5650);
PAINT GREEN (-5923 5650);
DISPLAY INVISIBLE (-5923 5650);
FORCEADD TAP..1
R 2
(-5925 5550);
FORCEPROP 3 LASTPIN (-5875 5550) SIG_NAME M_C_CPU0_SA_DQS_DP<4>
J 0
(-5865 5560);
DISPLAY 0.659574 (-5865 5560);
PAINT MONO (-5865 5560);
DISPLAY INVISIBLE (-5865 5560);
FORCEPROP 1 LASTPIN (-5875 5550) BN 4
J 2
(-5863 5558);
DISPLAY 0.489362 (-5863 5558);
PAINT GREEN (-5863 5558);
FORCEPROP 2 LAST CDS_LIB mstr_standard
J 2
(-5925 5550);
DISPLAY 0.723404 (-5925 5550);
PAINT MONO (-5925 5550);
DISPLAY INVISIBLE (-5925 5550);
FORCEPROP 1 LAST BODY_TYPE PLUMBING
J 2
(-5925 5600);
DISPLAY 0.872340 (-5925 5600);
PAINT GREEN (-5925 5600);
DISPLAY INVISIBLE (-5925 5600);
FORCEPROP 1 LAST HDL_TAP TRUE
J 2
(-6250 5425);
DISPLAY 0.872340 (-6250 5425);
DISPLAY INVISIBLE (-6250 5425);
FORCEPROP 1 LAST PATH I248
J 2
(-5923 5550);
DISPLAY 0.872340 (-5923 5550);
PAINT GREEN (-5923 5550);
DISPLAY INVISIBLE (-5923 5550);
FORCEADD TAP..1
R 2
(-5925 5450);
FORCEPROP 3 LASTPIN (-5875 5450) SIG_NAME M_C_CPU0_SA_DQS_DP<5>
J 0
(-5865 5460);
DISPLAY 0.659574 (-5865 5460);
PAINT MONO (-5865 5460);
DISPLAY INVISIBLE (-5865 5460);
FORCEPROP 1 LASTPIN (-5875 5450) BN 5
J 2
(-5863 5458);
DISPLAY 0.489362 (-5863 5458);
PAINT GREEN (-5863 5458);
FORCEPROP 2 LAST CDS_LIB mstr_standard
J 2
(-5925 5450);
DISPLAY 0.723404 (-5925 5450);
PAINT MONO (-5925 5450);
DISPLAY INVISIBLE (-5925 5450);
FORCEPROP 1 LAST BODY_TYPE PLUMBING
J 2
(-5925 5500);
DISPLAY 0.872340 (-5925 5500);
PAINT GREEN (-5925 5500);
DISPLAY INVISIBLE (-5925 5500);
FORCEPROP 1 LAST HDL_TAP TRUE
J 2
(-6250 5325);
DISPLAY 0.872340 (-6250 5325);
DISPLAY INVISIBLE (-6250 5325);
FORCEPROP 1 LAST PATH I249
J 2
(-5923 5450);
DISPLAY 0.872340 (-5923 5450);
PAINT GREEN (-5923 5450);
DISPLAY INVISIBLE (-5923 5450);
FORCEADD TAP..1
R 2
(-5925 5350);
FORCEPROP 3 LASTPIN (-5875 5350) SIG_NAME M_C_CPU0_SA_DQS_DP<6>
J 0
(-5865 5360);
DISPLAY 0.659574 (-5865 5360);
PAINT MONO (-5865 5360);
DISPLAY INVISIBLE (-5865 5360);
FORCEPROP 1 LASTPIN (-5875 5350) BN 6
J 2
(-5863 5358);
DISPLAY 0.489362 (-5863 5358);
PAINT GREEN (-5863 5358);
FORCEPROP 2 LAST CDS_LIB mstr_standard
J 2
(-5925 5350);
DISPLAY 0.723404 (-5925 5350);
PAINT MONO (-5925 5350);
DISPLAY INVISIBLE (-5925 5350);
FORCEPROP 1 LAST BODY_TYPE PLUMBING
J 2
(-5925 5400);
DISPLAY 0.872340 (-5925 5400);
PAINT GREEN (-5925 5400);
DISPLAY INVISIBLE (-5925 5400);
FORCEPROP 1 LAST HDL_TAP TRUE
J 2
(-6250 5225);
DISPLAY 0.872340 (-6250 5225);
DISPLAY INVISIBLE (-6250 5225);
FORCEPROP 1 LAST PATH I250
J 2
(-5923 5350);
DISPLAY 0.872340 (-5923 5350);
PAINT GREEN (-5923 5350);
DISPLAY INVISIBLE (-5923 5350);
FORCEADD TAP..1
R 2
(-5925 5250);
FORCEPROP 3 LASTPIN (-5875 5250) SIG_NAME M_C_CPU0_SA_DQS_DP<7>
J 0
(-5865 5260);
DISPLAY 0.659574 (-5865 5260);
PAINT MONO (-5865 5260);
DISPLAY INVISIBLE (-5865 5260);
FORCEPROP 1 LASTPIN (-5875 5250) BN 7
J 2
(-5863 5258);
DISPLAY 0.489362 (-5863 5258);
PAINT GREEN (-5863 5258);
FORCEPROP 2 LAST CDS_LIB mstr_standard
J 2
(-5925 5250);
DISPLAY 0.723404 (-5925 5250);
PAINT MONO (-5925 5250);
DISPLAY INVISIBLE (-5925 5250);
FORCEPROP 1 LAST BODY_TYPE PLUMBING
J 2
(-5925 5300);
DISPLAY 0.872340 (-5925 5300);
PAINT GREEN (-5925 5300);
DISPLAY INVISIBLE (-5925 5300);
FORCEPROP 1 LAST HDL_TAP TRUE
J 2
(-6250 5125);
DISPLAY 0.872340 (-6250 5125);
DISPLAY INVISIBLE (-6250 5125);
FORCEPROP 1 LAST PATH I251
J 2
(-5923 5250);
DISPLAY 0.872340 (-5923 5250);
PAINT GREEN (-5923 5250);
DISPLAY INVISIBLE (-5923 5250);
FORCEADD TAP..1
R 2
(-5925 5150);
FORCEPROP 3 LASTPIN (-5875 5150) SIG_NAME M_C_CPU0_SA_DQS_DP<8>
J 0
(-5865 5160);
DISPLAY 0.659574 (-5865 5160);
PAINT MONO (-5865 5160);
DISPLAY INVISIBLE (-5865 5160);
FORCEPROP 1 LASTPIN (-5875 5150) BN 8
J 2
(-5863 5158);
DISPLAY 0.489362 (-5863 5158);
PAINT GREEN (-5863 5158);
FORCEPROP 2 LAST CDS_LIB mstr_standard
J 2
(-5925 5150);
DISPLAY 0.723404 (-5925 5150);
PAINT MONO (-5925 5150);
DISPLAY INVISIBLE (-5925 5150);
FORCEPROP 1 LAST BODY_TYPE PLUMBING
J 2
(-5925 5200);
DISPLAY 0.872340 (-5925 5200);
PAINT GREEN (-5925 5200);
DISPLAY INVISIBLE (-5925 5200);
FORCEPROP 1 LAST HDL_TAP TRUE
J 2
(-6250 5025);
DISPLAY 0.872340 (-6250 5025);
DISPLAY INVISIBLE (-6250 5025);
FORCEPROP 1 LAST PATH I252
J 2
(-5923 5150);
DISPLAY 0.872340 (-5923 5150);
PAINT GREEN (-5923 5150);
DISPLAY INVISIBLE (-5923 5150);
FORCEADD TAP..1
R 2
(-5925 5050);
FORCEPROP 3 LASTPIN (-5875 5050) SIG_NAME M_C_CPU0_SA_DQS_DP<9>
J 0
(-5865 5060);
DISPLAY 0.659574 (-5865 5060);
PAINT MONO (-5865 5060);
DISPLAY INVISIBLE (-5865 5060);
FORCEPROP 1 LASTPIN (-5875 5050) BN 9
J 2
(-5863 5058);
DISPLAY 0.489362 (-5863 5058);
PAINT GREEN (-5863 5058);
FORCEPROP 2 LAST CDS_LIB mstr_standard
J 2
(-5925 5050);
DISPLAY 0.723404 (-5925 5050);
PAINT MONO (-5925 5050);
DISPLAY INVISIBLE (-5925 5050);
FORCEPROP 1 LAST BODY_TYPE PLUMBING
J 2
(-5925 5100);
DISPLAY 0.872340 (-5925 5100);
PAINT GREEN (-5925 5100);
DISPLAY INVISIBLE (-5925 5100);
FORCEPROP 1 LAST HDL_TAP TRUE
J 2
(-6250 4925);
DISPLAY 0.872340 (-6250 4925);
DISPLAY INVISIBLE (-6250 4925);
FORCEPROP 1 LAST PATH I253
J 2
(-5923 5050);
DISPLAY 0.872340 (-5923 5050);
PAINT GREEN (-5923 5050);
DISPLAY INVISIBLE (-5923 5050);
FORCEADD TAP..1
R 2
(-5925 4900);
FORCEPROP 3 LASTPIN (-5875 4900) SIG_NAME M_C_CPU0_SB_DQS_DP<0>
J 0
(-5865 4910);
DISPLAY 0.659574 (-5865 4910);
PAINT MONO (-5865 4910);
DISPLAY INVISIBLE (-5865 4910);
FORCEPROP 1 LASTPIN (-5875 4900) BN 0
J 2
(-5863 4908);
DISPLAY 0.489362 (-5863 4908);
PAINT GREEN (-5863 4908);
FORCEPROP 2 LAST CDS_LIB mstr_standard
J 2
(-5925 4900);
DISPLAY 0.723404 (-5925 4900);
PAINT MONO (-5925 4900);
DISPLAY INVISIBLE (-5925 4900);
FORCEPROP 1 LAST BODY_TYPE PLUMBING
J 2
(-5925 4950);
DISPLAY 0.872340 (-5925 4950);
PAINT GREEN (-5925 4950);
DISPLAY INVISIBLE (-5925 4950);
FORCEPROP 1 LAST HDL_TAP TRUE
J 2
(-6250 4775);
DISPLAY 0.872340 (-6250 4775);
DISPLAY INVISIBLE (-6250 4775);
FORCEPROP 1 LAST PATH I254
J 2
(-5923 4900);
DISPLAY 0.872340 (-5923 4900);
PAINT GREEN (-5923 4900);
DISPLAY INVISIBLE (-5923 4900);
FORCEADD TAP..1
R 2
(-5925 4800);
FORCEPROP 3 LASTPIN (-5875 4800) SIG_NAME M_C_CPU0_SB_DQS_DP<1>
J 0
(-5865 4810);
DISPLAY 0.659574 (-5865 4810);
PAINT MONO (-5865 4810);
DISPLAY INVISIBLE (-5865 4810);
FORCEPROP 1 LASTPIN (-5875 4800) BN 1
J 2
(-5863 4808);
DISPLAY 0.489362 (-5863 4808);
PAINT GREEN (-5863 4808);
FORCEPROP 2 LAST CDS_LIB mstr_standard
J 2
(-5925 4800);
DISPLAY 0.723404 (-5925 4800);
PAINT MONO (-5925 4800);
DISPLAY INVISIBLE (-5925 4800);
FORCEPROP 1 LAST BODY_TYPE PLUMBING
J 2
(-5925 4850);
DISPLAY 0.872340 (-5925 4850);
PAINT GREEN (-5925 4850);
DISPLAY INVISIBLE (-5925 4850);
FORCEPROP 1 LAST HDL_TAP TRUE
J 2
(-6250 4675);
DISPLAY 0.872340 (-6250 4675);
DISPLAY INVISIBLE (-6250 4675);
FORCEPROP 1 LAST PATH I255
J 2
(-5923 4800);
DISPLAY 0.872340 (-5923 4800);
PAINT GREEN (-5923 4800);
DISPLAY INVISIBLE (-5923 4800);
FORCEADD TAP..1
R 2
(-5925 4700);
FORCEPROP 3 LASTPIN (-5875 4700) SIG_NAME M_C_CPU0_SB_DQS_DP<2>
J 0
(-5865 4710);
DISPLAY 0.659574 (-5865 4710);
PAINT MONO (-5865 4710);
DISPLAY INVISIBLE (-5865 4710);
FORCEPROP 1 LASTPIN (-5875 4700) BN 2
J 2
(-5863 4708);
DISPLAY 0.489362 (-5863 4708);
PAINT GREEN (-5863 4708);
FORCEPROP 2 LAST CDS_LIB mstr_standard
J 2
(-5925 4700);
DISPLAY 0.723404 (-5925 4700);
PAINT MONO (-5925 4700);
DISPLAY INVISIBLE (-5925 4700);
FORCEPROP 1 LAST BODY_TYPE PLUMBING
J 2
(-5925 4750);
DISPLAY 0.872340 (-5925 4750);
PAINT GREEN (-5925 4750);
DISPLAY INVISIBLE (-5925 4750);
FORCEPROP 1 LAST HDL_TAP TRUE
J 2
(-6250 4575);
DISPLAY 0.872340 (-6250 4575);
DISPLAY INVISIBLE (-6250 4575);
FORCEPROP 1 LAST PATH I256
J 2
(-5923 4700);
DISPLAY 0.872340 (-5923 4700);
PAINT GREEN (-5923 4700);
DISPLAY INVISIBLE (-5923 4700);
FORCEADD TAP..1
R 2
(-5925 4500);
FORCEPROP 3 LASTPIN (-5875 4500) SIG_NAME M_C_CPU0_SB_DQS_DP<4>
J 0
(-5865 4510);
DISPLAY 0.659574 (-5865 4510);
PAINT MONO (-5865 4510);
DISPLAY INVISIBLE (-5865 4510);
FORCEPROP 1 LASTPIN (-5875 4500) BN 4
J 2
(-5863 4508);
DISPLAY 0.489362 (-5863 4508);
PAINT GREEN (-5863 4508);
FORCEPROP 2 LAST CDS_LIB mstr_standard
J 2
(-5925 4500);
DISPLAY 0.723404 (-5925 4500);
PAINT MONO (-5925 4500);
DISPLAY INVISIBLE (-5925 4500);
FORCEPROP 1 LAST BODY_TYPE PLUMBING
J 2
(-5925 4550);
DISPLAY 0.872340 (-5925 4550);
PAINT GREEN (-5925 4550);
DISPLAY INVISIBLE (-5925 4550);
FORCEPROP 1 LAST HDL_TAP TRUE
J 2
(-6250 4375);
DISPLAY 0.872340 (-6250 4375);
DISPLAY INVISIBLE (-6250 4375);
FORCEPROP 1 LAST PATH I257
J 2
(-5923 4500);
DISPLAY 0.872340 (-5923 4500);
PAINT GREEN (-5923 4500);
DISPLAY INVISIBLE (-5923 4500);
FORCEADD TAP..1
R 2
(-5925 4600);
FORCEPROP 3 LASTPIN (-5875 4600) SIG_NAME M_C_CPU0_SB_DQS_DP<3>
J 0
(-5865 4610);
DISPLAY 0.659574 (-5865 4610);
PAINT MONO (-5865 4610);
DISPLAY INVISIBLE (-5865 4610);
FORCEPROP 1 LASTPIN (-5875 4600) BN 3
J 2
(-5863 4608);
DISPLAY 0.489362 (-5863 4608);
PAINT GREEN (-5863 4608);
FORCEPROP 2 LAST CDS_LIB mstr_standard
J 2
(-5925 4600);
DISPLAY 0.723404 (-5925 4600);
PAINT MONO (-5925 4600);
DISPLAY INVISIBLE (-5925 4600);
FORCEPROP 1 LAST BODY_TYPE PLUMBING
J 2
(-5925 4650);
DISPLAY 0.872340 (-5925 4650);
PAINT GREEN (-5925 4650);
DISPLAY INVISIBLE (-5925 4650);
FORCEPROP 1 LAST HDL_TAP TRUE
J 2
(-6250 4475);
DISPLAY 0.872340 (-6250 4475);
DISPLAY INVISIBLE (-6250 4475);
FORCEPROP 1 LAST PATH I258
J 2
(-5923 4600);
DISPLAY 0.872340 (-5923 4600);
PAINT GREEN (-5923 4600);
DISPLAY INVISIBLE (-5923 4600);
FORCEADD TAP..1
R 2
(-5925 4400);
FORCEPROP 3 LASTPIN (-5875 4400) SIG_NAME M_C_CPU0_SB_DQS_DP<5>
J 0
(-5865 4410);
DISPLAY 0.659574 (-5865 4410);
PAINT MONO (-5865 4410);
DISPLAY INVISIBLE (-5865 4410);
FORCEPROP 1 LASTPIN (-5875 4400) BN 5
J 2
(-5863 4408);
DISPLAY 0.489362 (-5863 4408);
PAINT GREEN (-5863 4408);
FORCEPROP 2 LAST CDS_LIB mstr_standard
J 2
(-5925 4400);
DISPLAY 0.723404 (-5925 4400);
PAINT MONO (-5925 4400);
DISPLAY INVISIBLE (-5925 4400);
FORCEPROP 1 LAST BODY_TYPE PLUMBING
J 2
(-5925 4450);
DISPLAY 0.872340 (-5925 4450);
PAINT GREEN (-5925 4450);
DISPLAY INVISIBLE (-5925 4450);
FORCEPROP 1 LAST HDL_TAP TRUE
J 2
(-6250 4275);
DISPLAY 0.872340 (-6250 4275);
DISPLAY INVISIBLE (-6250 4275);
FORCEPROP 1 LAST PATH I259
J 2
(-5923 4400);
DISPLAY 0.872340 (-5923 4400);
PAINT GREEN (-5923 4400);
DISPLAY INVISIBLE (-5923 4400);
FORCEADD TAP..1
R 2
(-5925 4300);
FORCEPROP 3 LASTPIN (-5875 4300) SIG_NAME M_C_CPU0_SB_DQS_DP<6>
J 0
(-5865 4310);
DISPLAY 0.659574 (-5865 4310);
PAINT MONO (-5865 4310);
DISPLAY INVISIBLE (-5865 4310);
FORCEPROP 1 LASTPIN (-5875 4300) BN 6
J 2
(-5863 4308);
DISPLAY 0.489362 (-5863 4308);
PAINT GREEN (-5863 4308);
FORCEPROP 2 LAST CDS_LIB mstr_standard
J 2
(-5925 4300);
DISPLAY 0.723404 (-5925 4300);
PAINT MONO (-5925 4300);
DISPLAY INVISIBLE (-5925 4300);
FORCEPROP 1 LAST BODY_TYPE PLUMBING
J 2
(-5925 4350);
DISPLAY 0.872340 (-5925 4350);
PAINT GREEN (-5925 4350);
DISPLAY INVISIBLE (-5925 4350);
FORCEPROP 1 LAST HDL_TAP TRUE
J 2
(-6250 4175);
DISPLAY 0.872340 (-6250 4175);
DISPLAY INVISIBLE (-6250 4175);
FORCEPROP 1 LAST PATH I260
J 2
(-5923 4300);
DISPLAY 0.872340 (-5923 4300);
PAINT GREEN (-5923 4300);
DISPLAY INVISIBLE (-5923 4300);
FORCEADD TAP..1
R 2
(-5925 4100);
FORCEPROP 3 LASTPIN (-5875 4100) SIG_NAME M_C_CPU0_SB_DQS_DP<8>
J 0
(-5865 4110);
DISPLAY 0.659574 (-5865 4110);
PAINT MONO (-5865 4110);
DISPLAY INVISIBLE (-5865 4110);
FORCEPROP 1 LASTPIN (-5875 4100) BN 8
J 2
(-5863 4108);
DISPLAY 0.489362 (-5863 4108);
PAINT GREEN (-5863 4108);
FORCEPROP 2 LAST CDS_LIB mstr_standard
J 2
(-5925 4100);
DISPLAY 0.723404 (-5925 4100);
PAINT MONO (-5925 4100);
DISPLAY INVISIBLE (-5925 4100);
FORCEPROP 1 LAST BODY_TYPE PLUMBING
J 2
(-5925 4150);
DISPLAY 0.872340 (-5925 4150);
PAINT GREEN (-5925 4150);
DISPLAY INVISIBLE (-5925 4150);
FORCEPROP 1 LAST HDL_TAP TRUE
J 2
(-6250 3975);
DISPLAY 0.872340 (-6250 3975);
DISPLAY INVISIBLE (-6250 3975);
FORCEPROP 1 LAST PATH I261
J 2
(-5923 4100);
DISPLAY 0.872340 (-5923 4100);
PAINT GREEN (-5923 4100);
DISPLAY INVISIBLE (-5923 4100);
FORCEADD TAP..1
R 2
(-5925 4200);
FORCEPROP 3 LASTPIN (-5875 4200) SIG_NAME M_C_CPU0_SB_DQS_DP<7>
J 0
(-5865 4210);
DISPLAY 0.659574 (-5865 4210);
PAINT MONO (-5865 4210);
DISPLAY INVISIBLE (-5865 4210);
FORCEPROP 1 LASTPIN (-5875 4200) BN 7
J 2
(-5863 4208);
DISPLAY 0.489362 (-5863 4208);
PAINT GREEN (-5863 4208);
FORCEPROP 2 LAST CDS_LIB mstr_standard
J 2
(-5925 4200);
DISPLAY 0.723404 (-5925 4200);
PAINT MONO (-5925 4200);
DISPLAY INVISIBLE (-5925 4200);
FORCEPROP 1 LAST BODY_TYPE PLUMBING
J 2
(-5925 4250);
DISPLAY 0.872340 (-5925 4250);
PAINT GREEN (-5925 4250);
DISPLAY INVISIBLE (-5925 4250);
FORCEPROP 1 LAST HDL_TAP TRUE
J 2
(-6250 4075);
DISPLAY 0.872340 (-6250 4075);
DISPLAY INVISIBLE (-6250 4075);
FORCEPROP 1 LAST PATH I262
J 2
(-5923 4200);
DISPLAY 0.872340 (-5923 4200);
PAINT GREEN (-5923 4200);
DISPLAY INVISIBLE (-5923 4200);
FORCEADD TAP..1
R 2
(-6125 5800);
FORCEPROP 3 LASTPIN (-6075 5800) SIG_NAME M_C_CPU0_SA_DQS_DN<1>
J 0
(-6065 5810);
DISPLAY 0.659574 (-6065 5810);
PAINT MONO (-6065 5810);
DISPLAY INVISIBLE (-6065 5810);
FORCEPROP 1 LASTPIN (-6075 5800) BN 1
J 2
(-6063 5808);
DISPLAY 0.489362 (-6063 5808);
PAINT GREEN (-6063 5808);
FORCEPROP 2 LAST CDS_LIB mstr_standard
J 2
(-6125 5800);
DISPLAY 0.723404 (-6125 5800);
PAINT MONO (-6125 5800);
DISPLAY INVISIBLE (-6125 5800);
FORCEPROP 1 LAST BODY_TYPE PLUMBING
J 2
(-6125 5850);
DISPLAY 0.872340 (-6125 5850);
PAINT GREEN (-6125 5850);
DISPLAY INVISIBLE (-6125 5850);
FORCEPROP 1 LAST HDL_TAP TRUE
J 2
(-6450 5675);
DISPLAY 0.872340 (-6450 5675);
DISPLAY INVISIBLE (-6450 5675);
FORCEPROP 1 LAST PATH I263
J 2
(-6123 5800);
DISPLAY 0.872340 (-6123 5800);
PAINT GREEN (-6123 5800);
DISPLAY INVISIBLE (-6123 5800);
FORCEADD TAP..1
R 2
(-6125 5700);
FORCEPROP 3 LASTPIN (-6075 5700) SIG_NAME M_C_CPU0_SA_DQS_DN<2>
J 0
(-6065 5710);
DISPLAY 0.659574 (-6065 5710);
PAINT MONO (-6065 5710);
DISPLAY INVISIBLE (-6065 5710);
FORCEPROP 1 LASTPIN (-6075 5700) BN 2
J 2
(-6063 5708);
DISPLAY 0.489362 (-6063 5708);
PAINT GREEN (-6063 5708);
FORCEPROP 2 LAST CDS_LIB mstr_standard
J 2
(-6125 5700);
DISPLAY 0.723404 (-6125 5700);
PAINT MONO (-6125 5700);
DISPLAY INVISIBLE (-6125 5700);
FORCEPROP 1 LAST BODY_TYPE PLUMBING
J 2
(-6125 5750);
DISPLAY 0.872340 (-6125 5750);
PAINT GREEN (-6125 5750);
DISPLAY INVISIBLE (-6125 5750);
FORCEPROP 1 LAST HDL_TAP TRUE
J 2
(-6450 5575);
DISPLAY 0.872340 (-6450 5575);
DISPLAY INVISIBLE (-6450 5575);
FORCEPROP 1 LAST PATH I264
J 2
(-6123 5700);
DISPLAY 0.872340 (-6123 5700);
PAINT GREEN (-6123 5700);
DISPLAY INVISIBLE (-6123 5700);
FORCEADD TAP..1
R 2
(-6125 5900);
FORCEPROP 3 LASTPIN (-6075 5900) SIG_NAME M_C_CPU0_SA_DQS_DN<0>
J 0
(-6065 5910);
DISPLAY 0.659574 (-6065 5910);
PAINT MONO (-6065 5910);
DISPLAY INVISIBLE (-6065 5910);
FORCEPROP 1 LASTPIN (-6075 5900) BN 0
J 2
(-6063 5908);
DISPLAY 0.489362 (-6063 5908);
PAINT GREEN (-6063 5908);
FORCEPROP 2 LAST CDS_LIB mstr_standard
J 2
(-6125 5900);
DISPLAY 0.723404 (-6125 5900);
PAINT MONO (-6125 5900);
DISPLAY INVISIBLE (-6125 5900);
FORCEPROP 1 LAST BODY_TYPE PLUMBING
J 2
(-6125 5950);
DISPLAY 0.872340 (-6125 5950);
PAINT GREEN (-6125 5950);
DISPLAY INVISIBLE (-6125 5950);
FORCEPROP 1 LAST HDL_TAP TRUE
J 2
(-6450 5775);
DISPLAY 0.872340 (-6450 5775);
DISPLAY INVISIBLE (-6450 5775);
FORCEPROP 1 LAST PATH I265
J 2
(-6123 5900);
DISPLAY 0.872340 (-6123 5900);
PAINT GREEN (-6123 5900);
DISPLAY INVISIBLE (-6123 5900);
FORCEADD TAP..1
R 2
(-6125 5400);
FORCEPROP 3 LASTPIN (-6075 5400) SIG_NAME M_C_CPU0_SA_DQS_DN<5>
J 0
(-6065 5410);
DISPLAY 0.659574 (-6065 5410);
PAINT MONO (-6065 5410);
DISPLAY INVISIBLE (-6065 5410);
FORCEPROP 1 LASTPIN (-6075 5400) BN 5
J 2
(-6063 5408);
DISPLAY 0.489362 (-6063 5408);
PAINT GREEN (-6063 5408);
FORCEPROP 2 LAST CDS_LIB mstr_standard
J 2
(-6125 5400);
DISPLAY 0.723404 (-6125 5400);
PAINT MONO (-6125 5400);
DISPLAY INVISIBLE (-6125 5400);
FORCEPROP 1 LAST BODY_TYPE PLUMBING
J 2
(-6125 5450);
DISPLAY 0.872340 (-6125 5450);
PAINT GREEN (-6125 5450);
DISPLAY INVISIBLE (-6125 5450);
FORCEPROP 1 LAST HDL_TAP TRUE
J 2
(-6450 5275);
DISPLAY 0.872340 (-6450 5275);
DISPLAY INVISIBLE (-6450 5275);
FORCEPROP 1 LAST PATH I266
J 2
(-6123 5400);
DISPLAY 0.872340 (-6123 5400);
PAINT GREEN (-6123 5400);
DISPLAY INVISIBLE (-6123 5400);
FORCEADD TAP..1
R 2
(-6125 5600);
FORCEPROP 3 LASTPIN (-6075 5600) SIG_NAME M_C_CPU0_SA_DQS_DN<3>
J 0
(-6065 5610);
DISPLAY 0.659574 (-6065 5610);
PAINT MONO (-6065 5610);
DISPLAY INVISIBLE (-6065 5610);
FORCEPROP 1 LASTPIN (-6075 5600) BN 3
J 2
(-6063 5608);
DISPLAY 0.489362 (-6063 5608);
PAINT GREEN (-6063 5608);
FORCEPROP 2 LAST CDS_LIB mstr_standard
J 2
(-6125 5600);
DISPLAY 0.723404 (-6125 5600);
PAINT MONO (-6125 5600);
DISPLAY INVISIBLE (-6125 5600);
FORCEPROP 1 LAST BODY_TYPE PLUMBING
J 2
(-6125 5650);
DISPLAY 0.872340 (-6125 5650);
PAINT GREEN (-6125 5650);
DISPLAY INVISIBLE (-6125 5650);
FORCEPROP 1 LAST HDL_TAP TRUE
J 2
(-6450 5475);
DISPLAY 0.872340 (-6450 5475);
DISPLAY INVISIBLE (-6450 5475);
FORCEPROP 1 LAST PATH I267
J 2
(-6123 5600);
DISPLAY 0.872340 (-6123 5600);
PAINT GREEN (-6123 5600);
DISPLAY INVISIBLE (-6123 5600);
FORCEADD TAP..1
R 2
(-6125 5500);
FORCEPROP 3 LASTPIN (-6075 5500) SIG_NAME M_C_CPU0_SA_DQS_DN<4>
J 0
(-6065 5510);
DISPLAY 0.659574 (-6065 5510);
PAINT MONO (-6065 5510);
DISPLAY INVISIBLE (-6065 5510);
FORCEPROP 1 LASTPIN (-6075 5500) BN 4
J 2
(-6063 5508);
DISPLAY 0.489362 (-6063 5508);
PAINT GREEN (-6063 5508);
FORCEPROP 2 LAST CDS_LIB mstr_standard
J 2
(-6125 5500);
DISPLAY 0.723404 (-6125 5500);
PAINT MONO (-6125 5500);
DISPLAY INVISIBLE (-6125 5500);
FORCEPROP 1 LAST BODY_TYPE PLUMBING
J 2
(-6125 5550);
DISPLAY 0.872340 (-6125 5550);
PAINT GREEN (-6125 5550);
DISPLAY INVISIBLE (-6125 5550);
FORCEPROP 1 LAST HDL_TAP TRUE
J 2
(-6450 5375);
DISPLAY 0.872340 (-6450 5375);
DISPLAY INVISIBLE (-6450 5375);
FORCEPROP 1 LAST PATH I268
J 2
(-6123 5500);
DISPLAY 0.872340 (-6123 5500);
PAINT GREEN (-6123 5500);
DISPLAY INVISIBLE (-6123 5500);
FORCEADD TAP..1
R 2
(-6125 5100);
FORCEPROP 3 LASTPIN (-6075 5100) SIG_NAME M_C_CPU0_SA_DQS_DN<8>
J 0
(-6065 5110);
DISPLAY 0.659574 (-6065 5110);
PAINT MONO (-6065 5110);
DISPLAY INVISIBLE (-6065 5110);
FORCEPROP 1 LASTPIN (-6075 5100) BN 8
J 2
(-6063 5108);
DISPLAY 0.489362 (-6063 5108);
PAINT GREEN (-6063 5108);
FORCEPROP 2 LAST CDS_LIB mstr_standard
J 2
(-6125 5100);
DISPLAY 0.723404 (-6125 5100);
PAINT MONO (-6125 5100);
DISPLAY INVISIBLE (-6125 5100);
FORCEPROP 1 LAST BODY_TYPE PLUMBING
J 2
(-6125 5150);
DISPLAY 0.872340 (-6125 5150);
PAINT GREEN (-6125 5150);
DISPLAY INVISIBLE (-6125 5150);
FORCEPROP 1 LAST HDL_TAP TRUE
J 2
(-6450 4975);
DISPLAY 0.872340 (-6450 4975);
DISPLAY INVISIBLE (-6450 4975);
FORCEPROP 1 LAST PATH I269
J 2
(-6123 5100);
DISPLAY 0.872340 (-6123 5100);
PAINT GREEN (-6123 5100);
DISPLAY INVISIBLE (-6123 5100);
FORCEADD TAP..1
R 2
(-6125 5200);
FORCEPROP 3 LASTPIN (-6075 5200) SIG_NAME M_C_CPU0_SA_DQS_DN<7>
J 0
(-6065 5210);
DISPLAY 0.659574 (-6065 5210);
PAINT MONO (-6065 5210);
DISPLAY INVISIBLE (-6065 5210);
FORCEPROP 1 LASTPIN (-6075 5200) BN 7
J 2
(-6063 5208);
DISPLAY 0.489362 (-6063 5208);
PAINT GREEN (-6063 5208);
FORCEPROP 2 LAST CDS_LIB mstr_standard
J 2
(-6125 5200);
DISPLAY 0.723404 (-6125 5200);
PAINT MONO (-6125 5200);
DISPLAY INVISIBLE (-6125 5200);
FORCEPROP 1 LAST BODY_TYPE PLUMBING
J 2
(-6125 5250);
DISPLAY 0.872340 (-6125 5250);
PAINT GREEN (-6125 5250);
DISPLAY INVISIBLE (-6125 5250);
FORCEPROP 1 LAST HDL_TAP TRUE
J 2
(-6450 5075);
DISPLAY 0.872340 (-6450 5075);
DISPLAY INVISIBLE (-6450 5075);
FORCEPROP 1 LAST PATH I270
J 2
(-6123 5200);
DISPLAY 0.872340 (-6123 5200);
PAINT GREEN (-6123 5200);
DISPLAY INVISIBLE (-6123 5200);
FORCEADD TAP..1
R 2
(-6125 5300);
FORCEPROP 3 LASTPIN (-6075 5300) SIG_NAME M_C_CPU0_SA_DQS_DN<6>
J 0
(-6065 5310);
DISPLAY 0.659574 (-6065 5310);
PAINT MONO (-6065 5310);
DISPLAY INVISIBLE (-6065 5310);
FORCEPROP 1 LASTPIN (-6075 5300) BN 6
J 2
(-6063 5308);
DISPLAY 0.489362 (-6063 5308);
PAINT GREEN (-6063 5308);
FORCEPROP 2 LAST CDS_LIB mstr_standard
J 2
(-6125 5300);
DISPLAY 0.723404 (-6125 5300);
PAINT MONO (-6125 5300);
DISPLAY INVISIBLE (-6125 5300);
FORCEPROP 1 LAST BODY_TYPE PLUMBING
J 2
(-6125 5350);
DISPLAY 0.872340 (-6125 5350);
PAINT GREEN (-6125 5350);
DISPLAY INVISIBLE (-6125 5350);
FORCEPROP 1 LAST HDL_TAP TRUE
J 2
(-6450 5175);
DISPLAY 0.872340 (-6450 5175);
DISPLAY INVISIBLE (-6450 5175);
FORCEPROP 1 LAST PATH I271
J 2
(-6123 5300);
DISPLAY 0.872340 (-6123 5300);
PAINT GREEN (-6123 5300);
DISPLAY INVISIBLE (-6123 5300);
FORCEADD OFFPAGE..3
R 2
(-6825 5975);
FORCEPROP 2 LAST $XR0 88 
J 0
(-7074 5975);
DISPLAY 0.638298 (-7074 5975);
PAINT MONO (-7074 5975);
FORCEPROP 2 LAST CDS_LIB standard
J 0
(-6825 5975);
DISPLAY INVISIBLE (-6825 5975);
FORCEPROP 1 LAST OFFPAGE TRUE
J 2
(-7150 5850);
DISPLAY 0.872340 (-7150 5850);
PAINT GREEN (-7150 5850);
DISPLAY INVISIBLE (-7150 5850);
FORCEPROP 1 LAST COMMENT_BODY TRUE
J 2
(-6775 5875);
DISPLAY 0.872340 (-6775 5875);
PAINT GREEN (-6775 5875);
DISPLAY INVISIBLE (-6775 5875);
FORCEPROP 2 LAST PATH I272
J 0
(-7125 6025);
DISPLAY 1.021277 (-7125 6025);
DISPLAY INVISIBLE (-7125 6025);
FORCEADD OFFPAGE..3
R 2
(-6825 5925);
FORCEPROP 2 LAST $XR0 88 
J 0
(-7074 5925);
DISPLAY 0.638298 (-7074 5925);
PAINT MONO (-7074 5925);
FORCEPROP 2 LAST CDS_LIB standard
J 0
(-6825 5925);
DISPLAY INVISIBLE (-6825 5925);
FORCEPROP 1 LAST OFFPAGE TRUE
J 2
(-7150 5800);
DISPLAY 0.872340 (-7150 5800);
PAINT GREEN (-7150 5800);
DISPLAY INVISIBLE (-7150 5800);
FORCEPROP 1 LAST COMMENT_BODY TRUE
J 2
(-6775 5825);
DISPLAY 0.872340 (-6775 5825);
PAINT GREEN (-6775 5825);
DISPLAY INVISIBLE (-6775 5825);
FORCEPROP 2 LAST PATH I273
J 0
(-7125 5975);
DISPLAY 1.021277 (-7125 5975);
DISPLAY INVISIBLE (-7125 5975);
FORCEADD TAP..1
R 2
(-6125 4850);
FORCEPROP 3 LASTPIN (-6075 4850) SIG_NAME M_C_CPU0_SB_DQS_DN<0>
J 0
(-6065 4860);
DISPLAY 0.659574 (-6065 4860);
PAINT MONO (-6065 4860);
DISPLAY INVISIBLE (-6065 4860);
FORCEPROP 1 LASTPIN (-6075 4850) BN 0
J 2
(-6063 4858);
DISPLAY 0.489362 (-6063 4858);
PAINT GREEN (-6063 4858);
FORCEPROP 2 LAST CDS_LIB mstr_standard
J 2
(-6125 4850);
DISPLAY 0.723404 (-6125 4850);
PAINT MONO (-6125 4850);
DISPLAY INVISIBLE (-6125 4850);
FORCEPROP 1 LAST BODY_TYPE PLUMBING
J 2
(-6125 4900);
DISPLAY 0.872340 (-6125 4900);
PAINT GREEN (-6125 4900);
DISPLAY INVISIBLE (-6125 4900);
FORCEPROP 1 LAST HDL_TAP TRUE
J 2
(-6450 4725);
DISPLAY 0.872340 (-6450 4725);
DISPLAY INVISIBLE (-6450 4725);
FORCEPROP 1 LAST PATH I274
J 2
(-6123 4850);
DISPLAY 0.872340 (-6123 4850);
PAINT GREEN (-6123 4850);
DISPLAY INVISIBLE (-6123 4850);
FORCEADD TAP..1
R 2
(-6125 5000);
FORCEPROP 3 LASTPIN (-6075 5000) SIG_NAME M_C_CPU0_SA_DQS_DN<9>
J 0
(-6065 5010);
DISPLAY 0.659574 (-6065 5010);
PAINT MONO (-6065 5010);
DISPLAY INVISIBLE (-6065 5010);
FORCEPROP 1 LASTPIN (-6075 5000) BN 9
J 2
(-6063 5008);
DISPLAY 0.489362 (-6063 5008);
PAINT GREEN (-6063 5008);
FORCEPROP 2 LAST CDS_LIB mstr_standard
J 2
(-6125 5000);
DISPLAY 0.723404 (-6125 5000);
PAINT MONO (-6125 5000);
DISPLAY INVISIBLE (-6125 5000);
FORCEPROP 1 LAST BODY_TYPE PLUMBING
J 2
(-6125 5050);
DISPLAY 0.872340 (-6125 5050);
PAINT GREEN (-6125 5050);
DISPLAY INVISIBLE (-6125 5050);
FORCEPROP 1 LAST HDL_TAP TRUE
J 2
(-6450 4875);
DISPLAY 0.872340 (-6450 4875);
DISPLAY INVISIBLE (-6450 4875);
FORCEPROP 1 LAST PATH I275
J 2
(-6123 5000);
DISPLAY 0.872340 (-6123 5000);
PAINT GREEN (-6123 5000);
DISPLAY INVISIBLE (-6123 5000);
FORCEADD TAP..1
R 2
(-6125 4650);
FORCEPROP 3 LASTPIN (-6075 4650) SIG_NAME M_C_CPU0_SB_DQS_DN<2>
J 0
(-6065 4660);
DISPLAY 0.659574 (-6065 4660);
PAINT MONO (-6065 4660);
DISPLAY INVISIBLE (-6065 4660);
FORCEPROP 1 LASTPIN (-6075 4650) BN 2
J 2
(-6063 4658);
DISPLAY 0.489362 (-6063 4658);
PAINT GREEN (-6063 4658);
FORCEPROP 2 LAST CDS_LIB mstr_standard
J 2
(-6125 4650);
DISPLAY 0.723404 (-6125 4650);
PAINT MONO (-6125 4650);
DISPLAY INVISIBLE (-6125 4650);
FORCEPROP 1 LAST BODY_TYPE PLUMBING
J 2
(-6125 4700);
DISPLAY 0.872340 (-6125 4700);
PAINT GREEN (-6125 4700);
DISPLAY INVISIBLE (-6125 4700);
FORCEPROP 1 LAST HDL_TAP TRUE
J 2
(-6450 4525);
DISPLAY 0.872340 (-6450 4525);
DISPLAY INVISIBLE (-6450 4525);
FORCEPROP 1 LAST PATH I276
J 2
(-6123 4650);
DISPLAY 0.872340 (-6123 4650);
PAINT GREEN (-6123 4650);
DISPLAY INVISIBLE (-6123 4650);
FORCEADD TAP..1
R 2
(-6125 4750);
FORCEPROP 3 LASTPIN (-6075 4750) SIG_NAME M_C_CPU0_SB_DQS_DN<1>
J 0
(-6065 4760);
DISPLAY 0.659574 (-6065 4760);
PAINT MONO (-6065 4760);
DISPLAY INVISIBLE (-6065 4760);
FORCEPROP 1 LASTPIN (-6075 4750) BN 1
J 2
(-6063 4758);
DISPLAY 0.489362 (-6063 4758);
PAINT GREEN (-6063 4758);
FORCEPROP 2 LAST CDS_LIB mstr_standard
J 2
(-6125 4750);
DISPLAY 0.723404 (-6125 4750);
PAINT MONO (-6125 4750);
DISPLAY INVISIBLE (-6125 4750);
FORCEPROP 1 LAST BODY_TYPE PLUMBING
J 2
(-6125 4800);
DISPLAY 0.872340 (-6125 4800);
PAINT GREEN (-6125 4800);
DISPLAY INVISIBLE (-6125 4800);
FORCEPROP 1 LAST HDL_TAP TRUE
J 2
(-6450 4625);
DISPLAY 0.872340 (-6450 4625);
DISPLAY INVISIBLE (-6450 4625);
FORCEPROP 1 LAST PATH I277
J 2
(-6123 4750);
DISPLAY 0.872340 (-6123 4750);
PAINT GREEN (-6123 4750);
DISPLAY INVISIBLE (-6123 4750);
FORCEADD TAP..1
R 2
(-6125 4350);
FORCEPROP 3 LASTPIN (-6075 4350) SIG_NAME M_C_CPU0_SB_DQS_DN<5>
J 0
(-6065 4360);
DISPLAY 0.659574 (-6065 4360);
PAINT MONO (-6065 4360);
DISPLAY INVISIBLE (-6065 4360);
FORCEPROP 1 LASTPIN (-6075 4350) BN 5
J 2
(-6063 4358);
DISPLAY 0.489362 (-6063 4358);
PAINT GREEN (-6063 4358);
FORCEPROP 2 LAST CDS_LIB mstr_standard
J 2
(-6125 4350);
DISPLAY 0.723404 (-6125 4350);
PAINT MONO (-6125 4350);
DISPLAY INVISIBLE (-6125 4350);
FORCEPROP 1 LAST BODY_TYPE PLUMBING
J 2
(-6125 4400);
DISPLAY 0.872340 (-6125 4400);
PAINT GREEN (-6125 4400);
DISPLAY INVISIBLE (-6125 4400);
FORCEPROP 1 LAST HDL_TAP TRUE
J 2
(-6450 4225);
DISPLAY 0.872340 (-6450 4225);
DISPLAY INVISIBLE (-6450 4225);
FORCEPROP 1 LAST PATH I278
J 2
(-6123 4350);
DISPLAY 0.872340 (-6123 4350);
PAINT GREEN (-6123 4350);
DISPLAY INVISIBLE (-6123 4350);
FORCEADD TAP..1
R 2
(-6125 4550);
FORCEPROP 3 LASTPIN (-6075 4550) SIG_NAME M_C_CPU0_SB_DQS_DN<3>
J 0
(-6065 4560);
DISPLAY 0.659574 (-6065 4560);
PAINT MONO (-6065 4560);
DISPLAY INVISIBLE (-6065 4560);
FORCEPROP 1 LASTPIN (-6075 4550) BN 3
J 2
(-6063 4558);
DISPLAY 0.489362 (-6063 4558);
PAINT GREEN (-6063 4558);
FORCEPROP 2 LAST CDS_LIB mstr_standard
J 2
(-6125 4550);
DISPLAY 0.723404 (-6125 4550);
PAINT MONO (-6125 4550);
DISPLAY INVISIBLE (-6125 4550);
FORCEPROP 1 LAST BODY_TYPE PLUMBING
J 2
(-6125 4600);
DISPLAY 0.872340 (-6125 4600);
PAINT GREEN (-6125 4600);
DISPLAY INVISIBLE (-6125 4600);
FORCEPROP 1 LAST HDL_TAP TRUE
J 2
(-6450 4425);
DISPLAY 0.872340 (-6450 4425);
DISPLAY INVISIBLE (-6450 4425);
FORCEPROP 1 LAST PATH I279
J 2
(-6123 4550);
DISPLAY 0.872340 (-6123 4550);
PAINT GREEN (-6123 4550);
DISPLAY INVISIBLE (-6123 4550);
FORCEADD TAP..1
R 2
(-6125 4450);
FORCEPROP 3 LASTPIN (-6075 4450) SIG_NAME M_C_CPU0_SB_DQS_DN<4>
J 0
(-6065 4460);
DISPLAY 0.659574 (-6065 4460);
PAINT MONO (-6065 4460);
DISPLAY INVISIBLE (-6065 4460);
FORCEPROP 1 LASTPIN (-6075 4450) BN 4
J 2
(-6063 4458);
DISPLAY 0.489362 (-6063 4458);
PAINT GREEN (-6063 4458);
FORCEPROP 2 LAST CDS_LIB mstr_standard
J 2
(-6125 4450);
DISPLAY 0.723404 (-6125 4450);
PAINT MONO (-6125 4450);
DISPLAY INVISIBLE (-6125 4450);
FORCEPROP 1 LAST BODY_TYPE PLUMBING
J 2
(-6125 4500);
DISPLAY 0.872340 (-6125 4500);
PAINT GREEN (-6125 4500);
DISPLAY INVISIBLE (-6125 4500);
FORCEPROP 1 LAST HDL_TAP TRUE
J 2
(-6450 4325);
DISPLAY 0.872340 (-6450 4325);
DISPLAY INVISIBLE (-6450 4325);
FORCEPROP 1 LAST PATH I280
J 2
(-6123 4450);
DISPLAY 0.872340 (-6123 4450);
PAINT GREEN (-6123 4450);
DISPLAY INVISIBLE (-6123 4450);
FORCEADD TAP..1
R 2
(-6125 4150);
FORCEPROP 3 LASTPIN (-6075 4150) SIG_NAME M_C_CPU0_SB_DQS_DN<7>
J 0
(-6065 4160);
DISPLAY 0.659574 (-6065 4160);
PAINT MONO (-6065 4160);
DISPLAY INVISIBLE (-6065 4160);
FORCEPROP 1 LASTPIN (-6075 4150) BN 7
J 2
(-6063 4158);
DISPLAY 0.489362 (-6063 4158);
PAINT GREEN (-6063 4158);
FORCEPROP 2 LAST CDS_LIB mstr_standard
J 2
(-6125 4150);
DISPLAY 0.723404 (-6125 4150);
PAINT MONO (-6125 4150);
DISPLAY INVISIBLE (-6125 4150);
FORCEPROP 1 LAST BODY_TYPE PLUMBING
J 2
(-6125 4200);
DISPLAY 0.872340 (-6125 4200);
PAINT GREEN (-6125 4200);
DISPLAY INVISIBLE (-6125 4200);
FORCEPROP 1 LAST HDL_TAP TRUE
J 2
(-6450 4025);
DISPLAY 0.872340 (-6450 4025);
DISPLAY INVISIBLE (-6450 4025);
FORCEPROP 1 LAST PATH I281
J 2
(-6123 4150);
DISPLAY 0.872340 (-6123 4150);
PAINT GREEN (-6123 4150);
DISPLAY INVISIBLE (-6123 4150);
FORCEADD TAP..1
R 2
(-6125 4250);
FORCEPROP 3 LASTPIN (-6075 4250) SIG_NAME M_C_CPU0_SB_DQS_DN<6>
J 0
(-6065 4260);
DISPLAY 0.659574 (-6065 4260);
PAINT MONO (-6065 4260);
DISPLAY INVISIBLE (-6065 4260);
FORCEPROP 1 LASTPIN (-6075 4250) BN 6
J 2
(-6063 4258);
DISPLAY 0.489362 (-6063 4258);
PAINT GREEN (-6063 4258);
FORCEPROP 2 LAST CDS_LIB mstr_standard
J 2
(-6125 4250);
DISPLAY 0.723404 (-6125 4250);
PAINT MONO (-6125 4250);
DISPLAY INVISIBLE (-6125 4250);
FORCEPROP 1 LAST BODY_TYPE PLUMBING
J 2
(-6125 4300);
DISPLAY 0.872340 (-6125 4300);
PAINT GREEN (-6125 4300);
DISPLAY INVISIBLE (-6125 4300);
FORCEPROP 1 LAST HDL_TAP TRUE
J 2
(-6450 4125);
DISPLAY 0.872340 (-6450 4125);
DISPLAY INVISIBLE (-6450 4125);
FORCEPROP 1 LAST PATH I282
J 2
(-6123 4250);
DISPLAY 0.872340 (-6123 4250);
PAINT GREEN (-6123 4250);
DISPLAY INVISIBLE (-6123 4250);
FORCEADD OFFPAGE..3
R 2
(-6825 4925);
FORCEPROP 2 LAST $XR0 88 
J 0
(-7074 4925);
DISPLAY 0.638298 (-7074 4925);
PAINT MONO (-7074 4925);
FORCEPROP 2 LAST CDS_LIB standard
J 0
(-6825 4925);
DISPLAY INVISIBLE (-6825 4925);
FORCEPROP 1 LAST OFFPAGE TRUE
J 2
(-7150 4800);
DISPLAY 0.872340 (-7150 4800);
PAINT GREEN (-7150 4800);
DISPLAY INVISIBLE (-7150 4800);
FORCEPROP 1 LAST COMMENT_BODY TRUE
J 2
(-6775 4825);
DISPLAY 0.872340 (-6775 4825);
PAINT GREEN (-6775 4825);
DISPLAY INVISIBLE (-6775 4825);
FORCEPROP 2 LAST PATH I283
J 0
(-7125 4975);
DISPLAY 1.021277 (-7125 4975);
DISPLAY INVISIBLE (-7125 4975);
FORCEADD OFFPAGE..3
R 2
(-6825 4875);
FORCEPROP 2 LAST $XR0 88 
J 0
(-7074 4875);
DISPLAY 0.638298 (-7074 4875);
PAINT MONO (-7074 4875);
FORCEPROP 2 LAST CDS_LIB standard
J 0
(-6825 4875);
DISPLAY INVISIBLE (-6825 4875);
FORCEPROP 1 LAST OFFPAGE TRUE
J 2
(-7150 4750);
DISPLAY 0.872340 (-7150 4750);
PAINT GREEN (-7150 4750);
DISPLAY INVISIBLE (-7150 4750);
FORCEPROP 1 LAST COMMENT_BODY TRUE
J 2
(-6775 4775);
DISPLAY 0.872340 (-6775 4775);
PAINT GREEN (-6775 4775);
DISPLAY INVISIBLE (-6775 4775);
FORCEPROP 2 LAST PATH I284
J 0
(-7125 4925);
DISPLAY 1.021277 (-7125 4925);
DISPLAY INVISIBLE (-7125 4925);
FORCEADD TAP..1
R 2
(-5925 4000);
FORCEPROP 3 LASTPIN (-5875 4000) SIG_NAME M_C_CPU0_SB_DQS_DP<9>
J 0
(-5865 4010);
DISPLAY 0.659574 (-5865 4010);
PAINT MONO (-5865 4010);
DISPLAY INVISIBLE (-5865 4010);
FORCEPROP 1 LASTPIN (-5875 4000) BN 9
J 2
(-5863 4008);
DISPLAY 0.489362 (-5863 4008);
PAINT GREEN (-5863 4008);
FORCEPROP 2 LAST CDS_LIB mstr_standard
J 2
(-5925 4000);
DISPLAY 0.723404 (-5925 4000);
PAINT MONO (-5925 4000);
DISPLAY INVISIBLE (-5925 4000);
FORCEPROP 1 LAST BODY_TYPE PLUMBING
J 2
(-5925 4050);
DISPLAY 0.872340 (-5925 4050);
PAINT GREEN (-5925 4050);
DISPLAY INVISIBLE (-5925 4050);
FORCEPROP 1 LAST HDL_TAP TRUE
J 2
(-6250 3875);
DISPLAY 0.872340 (-6250 3875);
DISPLAY INVISIBLE (-6250 3875);
FORCEPROP 1 LAST PATH I285
J 2
(-5923 4000);
DISPLAY 0.872340 (-5923 4000);
PAINT GREEN (-5923 4000);
DISPLAY INVISIBLE (-5923 4000);
FORCEADD TAP..1
R 2
(-6125 3950);
FORCEPROP 3 LASTPIN (-6075 3950) SIG_NAME M_C_CPU0_SB_DQS_DN<9>
J 0
(-6065 3960);
DISPLAY 0.659574 (-6065 3960);
PAINT MONO (-6065 3960);
DISPLAY INVISIBLE (-6065 3960);
FORCEPROP 1 LASTPIN (-6075 3950) BN 9
J 2
(-6063 3958);
DISPLAY 0.489362 (-6063 3958);
PAINT GREEN (-6063 3958);
FORCEPROP 2 LAST CDS_LIB mstr_standard
J 2
(-6125 3950);
DISPLAY 0.723404 (-6125 3950);
PAINT MONO (-6125 3950);
DISPLAY INVISIBLE (-6125 3950);
FORCEPROP 1 LAST BODY_TYPE PLUMBING
J 2
(-6125 4000);
DISPLAY 0.872340 (-6125 4000);
PAINT GREEN (-6125 4000);
DISPLAY INVISIBLE (-6125 4000);
FORCEPROP 1 LAST HDL_TAP TRUE
J 2
(-6450 3825);
DISPLAY 0.872340 (-6450 3825);
DISPLAY INVISIBLE (-6450 3825);
FORCEPROP 1 LAST PATH I286
J 2
(-6123 3950);
DISPLAY 0.872340 (-6123 3950);
PAINT GREEN (-6123 3950);
DISPLAY INVISIBLE (-6123 3950);
FORCEADD TAP..1
R 2
(-6125 4050);
FORCEPROP 3 LASTPIN (-6075 4050) SIG_NAME M_C_CPU0_SB_DQS_DN<8>
J 0
(-6065 4060);
DISPLAY 0.659574 (-6065 4060);
PAINT MONO (-6065 4060);
DISPLAY INVISIBLE (-6065 4060);
FORCEPROP 1 LASTPIN (-6075 4050) BN 8
J 2
(-6063 4058);
DISPLAY 0.489362 (-6063 4058);
PAINT GREEN (-6063 4058);
FORCEPROP 2 LAST CDS_LIB mstr_standard
J 2
(-6125 4050);
DISPLAY 0.723404 (-6125 4050);
PAINT MONO (-6125 4050);
DISPLAY INVISIBLE (-6125 4050);
FORCEPROP 1 LAST BODY_TYPE PLUMBING
J 2
(-6125 4100);
DISPLAY 0.872340 (-6125 4100);
PAINT GREEN (-6125 4100);
DISPLAY INVISIBLE (-6125 4100);
FORCEPROP 1 LAST HDL_TAP TRUE
J 2
(-6450 3925);
DISPLAY 0.872340 (-6450 3925);
DISPLAY INVISIBLE (-6450 3925);
FORCEPROP 1 LAST PATH I287
J 2
(-6123 4050);
DISPLAY 0.872340 (-6123 4050);
PAINT GREEN (-6123 4050);
DISPLAY INVISIBLE (-6123 4050);
FORCEADD TAP..1
R 2
(-6125 3750);
FORCEPROP 3 LASTPIN (-6075 3750) SIG_NAME M_C_CPU0_SA_CA<1>
J 0
(-6065 3760);
DISPLAY 0.659574 (-6065 3760);
PAINT MONO (-6065 3760);
DISPLAY INVISIBLE (-6065 3760);
FORCEPROP 1 LASTPIN (-6075 3750) BN 1
J 2
(-6063 3758);
DISPLAY 0.489362 (-6063 3758);
PAINT GREEN (-6063 3758);
FORCEPROP 2 LAST CDS_LIB mstr_standard
J 0
(-6125 3750);
DISPLAY 0.723404 (-6125 3750);
PAINT MONO (-6125 3750);
DISPLAY INVISIBLE (-6125 3750);
FORCEPROP 1 LAST BODY_TYPE PLUMBING
J 2
(-6125 3800);
DISPLAY 0.872340 (-6125 3800);
PAINT GREEN (-6125 3800);
DISPLAY INVISIBLE (-6125 3800);
FORCEPROP 1 LAST HDL_TAP TRUE
J 2
(-6450 3625);
DISPLAY 0.872340 (-6450 3625);
DISPLAY INVISIBLE (-6450 3625);
FORCEPROP 1 LAST PATH I288
J 2
(-6123 3750);
DISPLAY 0.872340 (-6123 3750);
PAINT GREEN (-6123 3750);
DISPLAY INVISIBLE (-6123 3750);
FORCEADD TAP..1
R 2
(-6125 3800);
FORCEPROP 3 LASTPIN (-6075 3800) SIG_NAME M_C_CPU0_SA_CA<0>
J 0
(-6065 3810);
DISPLAY 0.659574 (-6065 3810);
PAINT MONO (-6065 3810);
DISPLAY INVISIBLE (-6065 3810);
FORCEPROP 1 LASTPIN (-6075 3800) BN 0
J 2
(-6063 3808);
DISPLAY 0.489362 (-6063 3808);
PAINT GREEN (-6063 3808);
FORCEPROP 2 LAST CDS_LIB mstr_standard
J 0
(-6125 3800);
DISPLAY 0.723404 (-6125 3800);
PAINT MONO (-6125 3800);
DISPLAY INVISIBLE (-6125 3800);
FORCEPROP 1 LAST BODY_TYPE PLUMBING
J 2
(-6125 3850);
DISPLAY 0.872340 (-6125 3850);
PAINT GREEN (-6125 3850);
DISPLAY INVISIBLE (-6125 3850);
FORCEPROP 1 LAST HDL_TAP TRUE
J 2
(-6450 3675);
DISPLAY 0.872340 (-6450 3675);
DISPLAY INVISIBLE (-6450 3675);
FORCEPROP 1 LAST PATH I289
J 2
(-6123 3800);
DISPLAY 0.872340 (-6123 3800);
PAINT GREEN (-6123 3800);
DISPLAY INVISIBLE (-6123 3800);
FORCEADD TAP..1
R 2
(-6125 3700);
FORCEPROP 3 LASTPIN (-6075 3700) SIG_NAME M_C_CPU0_SA_CA<2>
J 0
(-6065 3710);
DISPLAY 0.659574 (-6065 3710);
PAINT MONO (-6065 3710);
DISPLAY INVISIBLE (-6065 3710);
FORCEPROP 1 LASTPIN (-6075 3700) BN 2
J 2
(-6063 3708);
DISPLAY 0.489362 (-6063 3708);
PAINT GREEN (-6063 3708);
FORCEPROP 2 LAST CDS_LIB mstr_standard
J 0
(-6125 3700);
DISPLAY 0.723404 (-6125 3700);
PAINT MONO (-6125 3700);
DISPLAY INVISIBLE (-6125 3700);
FORCEPROP 1 LAST BODY_TYPE PLUMBING
J 2
(-6125 3750);
DISPLAY 0.872340 (-6125 3750);
PAINT GREEN (-6125 3750);
DISPLAY INVISIBLE (-6125 3750);
FORCEPROP 1 LAST HDL_TAP TRUE
J 2
(-6450 3575);
DISPLAY 0.872340 (-6450 3575);
DISPLAY INVISIBLE (-6450 3575);
FORCEPROP 1 LAST PATH I290
J 2
(-6123 3700);
DISPLAY 0.872340 (-6123 3700);
PAINT GREEN (-6123 3700);
DISPLAY INVISIBLE (-6123 3700);
FORCEADD TAP..1
R 2
(-6125 3650);
FORCEPROP 3 LASTPIN (-6075 3650) SIG_NAME M_C_CPU0_SA_CA<3>
J 0
(-6065 3660);
DISPLAY 0.659574 (-6065 3660);
PAINT MONO (-6065 3660);
DISPLAY INVISIBLE (-6065 3660);
FORCEPROP 1 LASTPIN (-6075 3650) BN 3
J 2
(-6063 3658);
DISPLAY 0.489362 (-6063 3658);
PAINT GREEN (-6063 3658);
FORCEPROP 2 LAST CDS_LIB mstr_standard
J 0
(-6125 3650);
DISPLAY 0.723404 (-6125 3650);
PAINT MONO (-6125 3650);
DISPLAY INVISIBLE (-6125 3650);
FORCEPROP 1 LAST BODY_TYPE PLUMBING
J 2
(-6125 3700);
DISPLAY 0.872340 (-6125 3700);
PAINT GREEN (-6125 3700);
DISPLAY INVISIBLE (-6125 3700);
FORCEPROP 1 LAST HDL_TAP TRUE
J 2
(-6450 3525);
DISPLAY 0.872340 (-6450 3525);
DISPLAY INVISIBLE (-6450 3525);
FORCEPROP 1 LAST PATH I291
J 2
(-6123 3650);
DISPLAY 0.872340 (-6123 3650);
PAINT GREEN (-6123 3650);
DISPLAY INVISIBLE (-6123 3650);
FORCEADD TAP..1
R 2
(-6125 3600);
FORCEPROP 3 LASTPIN (-6075 3600) SIG_NAME M_C_CPU0_SA_CA<4>
J 0
(-6065 3610);
DISPLAY 0.659574 (-6065 3610);
PAINT MONO (-6065 3610);
DISPLAY INVISIBLE (-6065 3610);
FORCEPROP 1 LASTPIN (-6075 3600) BN 4
J 2
(-6063 3608);
DISPLAY 0.489362 (-6063 3608);
PAINT GREEN (-6063 3608);
FORCEPROP 2 LAST CDS_LIB mstr_standard
J 0
(-6125 3600);
DISPLAY 0.723404 (-6125 3600);
PAINT MONO (-6125 3600);
DISPLAY INVISIBLE (-6125 3600);
FORCEPROP 1 LAST BODY_TYPE PLUMBING
J 2
(-6125 3650);
DISPLAY 0.872340 (-6125 3650);
PAINT GREEN (-6125 3650);
DISPLAY INVISIBLE (-6125 3650);
FORCEPROP 1 LAST HDL_TAP TRUE
J 2
(-6450 3475);
DISPLAY 0.872340 (-6450 3475);
DISPLAY INVISIBLE (-6450 3475);
FORCEPROP 1 LAST PATH I292
J 2
(-6123 3600);
DISPLAY 0.872340 (-6123 3600);
PAINT GREEN (-6123 3600);
DISPLAY INVISIBLE (-6123 3600);
FORCEADD TAP..1
R 2
(-6125 3550);
FORCEPROP 3 LASTPIN (-6075 3550) SIG_NAME M_C_CPU0_SA_CA<5>
J 0
(-6065 3560);
DISPLAY 0.659574 (-6065 3560);
PAINT MONO (-6065 3560);
DISPLAY INVISIBLE (-6065 3560);
FORCEPROP 1 LASTPIN (-6075 3550) BN 5
J 2
(-6063 3558);
DISPLAY 0.489362 (-6063 3558);
PAINT GREEN (-6063 3558);
FORCEPROP 2 LAST CDS_LIB mstr_standard
J 0
(-6125 3550);
DISPLAY 0.723404 (-6125 3550);
PAINT MONO (-6125 3550);
DISPLAY INVISIBLE (-6125 3550);
FORCEPROP 1 LAST BODY_TYPE PLUMBING
J 2
(-6125 3600);
DISPLAY 0.872340 (-6125 3600);
PAINT GREEN (-6125 3600);
DISPLAY INVISIBLE (-6125 3600);
FORCEPROP 1 LAST HDL_TAP TRUE
J 2
(-6450 3425);
DISPLAY 0.872340 (-6450 3425);
DISPLAY INVISIBLE (-6450 3425);
FORCEPROP 1 LAST PATH I293
J 2
(-6123 3550);
DISPLAY 0.872340 (-6123 3550);
PAINT GREEN (-6123 3550);
DISPLAY INVISIBLE (-6123 3550);
FORCEADD TAP..1
R 2
(-6125 3500);
FORCEPROP 3 LASTPIN (-6075 3500) SIG_NAME M_C_CPU0_SA_CA<6>
J 0
(-6065 3510);
DISPLAY 0.659574 (-6065 3510);
PAINT MONO (-6065 3510);
DISPLAY INVISIBLE (-6065 3510);
FORCEPROP 1 LASTPIN (-6075 3500) BN 6
J 2
(-6063 3508);
DISPLAY 0.489362 (-6063 3508);
PAINT GREEN (-6063 3508);
FORCEPROP 2 LAST CDS_LIB mstr_standard
J 0
(-6125 3500);
DISPLAY 0.723404 (-6125 3500);
PAINT MONO (-6125 3500);
DISPLAY INVISIBLE (-6125 3500);
FORCEPROP 1 LAST BODY_TYPE PLUMBING
J 2
(-6125 3550);
DISPLAY 0.872340 (-6125 3550);
PAINT GREEN (-6125 3550);
DISPLAY INVISIBLE (-6125 3550);
FORCEPROP 1 LAST HDL_TAP TRUE
J 2
(-6450 3375);
DISPLAY 0.872340 (-6450 3375);
DISPLAY INVISIBLE (-6450 3375);
FORCEPROP 1 LAST PATH I294
J 2
(-6123 3500);
DISPLAY 0.872340 (-6123 3500);
PAINT GREEN (-6123 3500);
DISPLAY INVISIBLE (-6123 3500);
FORCEADD TAP..1
R 2
(-6125 3400);
FORCEPROP 3 LASTPIN (-6075 3400) SIG_NAME M_C_CPU0_SB_CA<0>
J 0
(-6065 3410);
DISPLAY 0.659574 (-6065 3410);
PAINT MONO (-6065 3410);
DISPLAY INVISIBLE (-6065 3410);
FORCEPROP 1 LASTPIN (-6075 3400) BN 0
J 2
(-6063 3408);
DISPLAY 0.489362 (-6063 3408);
PAINT GREEN (-6063 3408);
FORCEPROP 2 LAST CDS_LIB mstr_standard
J 0
(-6125 3400);
DISPLAY 0.723404 (-6125 3400);
PAINT MONO (-6125 3400);
DISPLAY INVISIBLE (-6125 3400);
FORCEPROP 1 LAST BODY_TYPE PLUMBING
J 2
(-6125 3450);
DISPLAY 0.872340 (-6125 3450);
PAINT GREEN (-6125 3450);
DISPLAY INVISIBLE (-6125 3450);
FORCEPROP 1 LAST HDL_TAP TRUE
J 2
(-6450 3275);
DISPLAY 0.872340 (-6450 3275);
DISPLAY INVISIBLE (-6450 3275);
FORCEPROP 1 LAST PATH I295
J 2
(-6123 3400);
DISPLAY 0.872340 (-6123 3400);
PAINT GREEN (-6123 3400);
DISPLAY INVISIBLE (-6123 3400);
FORCEADD TAP..1
R 2
(-6125 3350);
FORCEPROP 3 LASTPIN (-6075 3350) SIG_NAME M_C_CPU0_SB_CA<1>
J 0
(-6065 3360);
DISPLAY 0.659574 (-6065 3360);
PAINT MONO (-6065 3360);
DISPLAY INVISIBLE (-6065 3360);
FORCEPROP 1 LASTPIN (-6075 3350) BN 1
J 2
(-6063 3358);
DISPLAY 0.489362 (-6063 3358);
PAINT GREEN (-6063 3358);
FORCEPROP 2 LAST CDS_LIB mstr_standard
J 0
(-6125 3350);
DISPLAY 0.723404 (-6125 3350);
PAINT MONO (-6125 3350);
DISPLAY INVISIBLE (-6125 3350);
FORCEPROP 1 LAST BODY_TYPE PLUMBING
J 2
(-6125 3400);
DISPLAY 0.872340 (-6125 3400);
PAINT GREEN (-6125 3400);
DISPLAY INVISIBLE (-6125 3400);
FORCEPROP 1 LAST HDL_TAP TRUE
J 2
(-6450 3225);
DISPLAY 0.872340 (-6450 3225);
DISPLAY INVISIBLE (-6450 3225);
FORCEPROP 1 LAST PATH I296
J 2
(-6123 3350);
DISPLAY 0.872340 (-6123 3350);
PAINT GREEN (-6123 3350);
DISPLAY INVISIBLE (-6123 3350);
FORCEADD TAP..1
R 2
(-6125 3250);
FORCEPROP 3 LASTPIN (-6075 3250) SIG_NAME M_C_CPU0_SB_CA<3>
J 0
(-6065 3260);
DISPLAY 0.659574 (-6065 3260);
PAINT MONO (-6065 3260);
DISPLAY INVISIBLE (-6065 3260);
FORCEPROP 1 LASTPIN (-6075 3250) BN 3
J 2
(-6063 3258);
DISPLAY 0.489362 (-6063 3258);
PAINT GREEN (-6063 3258);
FORCEPROP 2 LAST CDS_LIB mstr_standard
J 0
(-6125 3250);
DISPLAY 0.723404 (-6125 3250);
PAINT MONO (-6125 3250);
DISPLAY INVISIBLE (-6125 3250);
FORCEPROP 1 LAST BODY_TYPE PLUMBING
J 2
(-6125 3300);
DISPLAY 0.872340 (-6125 3300);
PAINT GREEN (-6125 3300);
DISPLAY INVISIBLE (-6125 3300);
FORCEPROP 1 LAST HDL_TAP TRUE
J 2
(-6450 3125);
DISPLAY 0.872340 (-6450 3125);
DISPLAY INVISIBLE (-6450 3125);
FORCEPROP 1 LAST PATH I297
J 2
(-6123 3250);
DISPLAY 0.872340 (-6123 3250);
PAINT GREEN (-6123 3250);
DISPLAY INVISIBLE (-6123 3250);
FORCEADD TAP..1
R 2
(-6125 3300);
FORCEPROP 3 LASTPIN (-6075 3300) SIG_NAME M_C_CPU0_SB_CA<2>
J 0
(-6065 3310);
DISPLAY 0.659574 (-6065 3310);
PAINT MONO (-6065 3310);
DISPLAY INVISIBLE (-6065 3310);
FORCEPROP 1 LASTPIN (-6075 3300) BN 2
J 2
(-6063 3308);
DISPLAY 0.489362 (-6063 3308);
PAINT GREEN (-6063 3308);
FORCEPROP 2 LAST CDS_LIB mstr_standard
J 0
(-6125 3300);
DISPLAY 0.723404 (-6125 3300);
PAINT MONO (-6125 3300);
DISPLAY INVISIBLE (-6125 3300);
FORCEPROP 1 LAST BODY_TYPE PLUMBING
J 2
(-6125 3350);
DISPLAY 0.872340 (-6125 3350);
PAINT GREEN (-6125 3350);
DISPLAY INVISIBLE (-6125 3350);
FORCEPROP 1 LAST HDL_TAP TRUE
J 2
(-6450 3175);
DISPLAY 0.872340 (-6450 3175);
DISPLAY INVISIBLE (-6450 3175);
FORCEPROP 1 LAST PATH I298
J 2
(-6123 3300);
DISPLAY 0.872340 (-6123 3300);
PAINT GREEN (-6123 3300);
DISPLAY INVISIBLE (-6123 3300);
FORCEADD TAP..1
R 2
(-6125 3200);
FORCEPROP 3 LASTPIN (-6075 3200) SIG_NAME M_C_CPU0_SB_CA<4>
J 0
(-6065 3210);
DISPLAY 0.659574 (-6065 3210);
PAINT MONO (-6065 3210);
DISPLAY INVISIBLE (-6065 3210);
FORCEPROP 1 LASTPIN (-6075 3200) BN 4
J 2
(-6063 3208);
DISPLAY 0.489362 (-6063 3208);
PAINT GREEN (-6063 3208);
FORCEPROP 2 LAST CDS_LIB mstr_standard
J 0
(-6125 3200);
DISPLAY 0.723404 (-6125 3200);
PAINT MONO (-6125 3200);
DISPLAY INVISIBLE (-6125 3200);
FORCEPROP 1 LAST BODY_TYPE PLUMBING
J 2
(-6125 3250);
DISPLAY 0.872340 (-6125 3250);
PAINT GREEN (-6125 3250);
DISPLAY INVISIBLE (-6125 3250);
FORCEPROP 1 LAST HDL_TAP TRUE
J 2
(-6450 3075);
DISPLAY 0.872340 (-6450 3075);
DISPLAY INVISIBLE (-6450 3075);
FORCEPROP 1 LAST PATH I299
J 2
(-6123 3200);
DISPLAY 0.872340 (-6123 3200);
PAINT GREEN (-6123 3200);
DISPLAY INVISIBLE (-6123 3200);
FORCEADD TAP..1
R 2
(-6125 3150);
FORCEPROP 3 LASTPIN (-6075 3150) SIG_NAME M_C_CPU0_SB_CA<5>
J 0
(-6065 3160);
DISPLAY 0.659574 (-6065 3160);
PAINT MONO (-6065 3160);
DISPLAY INVISIBLE (-6065 3160);
FORCEPROP 1 LASTPIN (-6075 3150) BN 5
J 2
(-6063 3158);
DISPLAY 0.489362 (-6063 3158);
PAINT GREEN (-6063 3158);
FORCEPROP 2 LAST CDS_LIB mstr_standard
J 0
(-6125 3150);
DISPLAY 0.723404 (-6125 3150);
PAINT MONO (-6125 3150);
DISPLAY INVISIBLE (-6125 3150);
FORCEPROP 1 LAST BODY_TYPE PLUMBING
J 2
(-6125 3200);
DISPLAY 0.872340 (-6125 3200);
PAINT GREEN (-6125 3200);
DISPLAY INVISIBLE (-6125 3200);
FORCEPROP 1 LAST HDL_TAP TRUE
J 2
(-6450 3025);
DISPLAY 0.872340 (-6450 3025);
DISPLAY INVISIBLE (-6450 3025);
FORCEPROP 1 LAST PATH I300
J 2
(-6123 3150);
DISPLAY 0.872340 (-6123 3150);
PAINT GREEN (-6123 3150);
DISPLAY INVISIBLE (-6123 3150);
FORCEADD TAP..1
R 2
(-6125 3100);
FORCEPROP 3 LASTPIN (-6075 3100) SIG_NAME M_C_CPU0_SB_CA<6>
J 0
(-6065 3110);
DISPLAY 0.659574 (-6065 3110);
PAINT MONO (-6065 3110);
DISPLAY INVISIBLE (-6065 3110);
FORCEPROP 1 LASTPIN (-6075 3100) BN 6
J 2
(-6063 3108);
DISPLAY 0.489362 (-6063 3108);
PAINT GREEN (-6063 3108);
FORCEPROP 2 LAST CDS_LIB mstr_standard
J 0
(-6125 3100);
DISPLAY 0.723404 (-6125 3100);
PAINT MONO (-6125 3100);
DISPLAY INVISIBLE (-6125 3100);
FORCEPROP 1 LAST BODY_TYPE PLUMBING
J 2
(-6125 3150);
DISPLAY 0.872340 (-6125 3150);
PAINT GREEN (-6125 3150);
DISPLAY INVISIBLE (-6125 3150);
FORCEPROP 1 LAST HDL_TAP TRUE
J 2
(-6450 2975);
DISPLAY 0.872340 (-6450 2975);
DISPLAY INVISIBLE (-6450 2975);
FORCEPROP 1 LAST PATH I301
J 2
(-6123 3100);
DISPLAY 0.872340 (-6123 3100);
PAINT GREEN (-6123 3100);
DISPLAY INVISIBLE (-6123 3100);
FORCEADD OFFPAGE..2
R 2
(-6725 3825);
FORCEPROP 2 LAST $XR0 88 
J 0
(-6979 3825);
DISPLAY 0.638298 (-6979 3825);
PAINT MONO (-6979 3825);
FORCEPROP 2 LAST CDS_LIB standard
J 0
(-6725 3825);
DISPLAY INVISIBLE (-6725 3825);
FORCEPROP 1 LAST OFFPAGE TRUE
J 2
(-7050 3700);
DISPLAY 0.872340 (-7050 3700);
PAINT GREEN (-7050 3700);
DISPLAY INVISIBLE (-7050 3700);
FORCEPROP 1 LAST COMMENT_BODY TRUE
J 2
(-6680 3730);
DISPLAY 0.872340 (-6680 3730);
PAINT GREEN (-6680 3730);
DISPLAY INVISIBLE (-6680 3730);
FORCEPROP 2 LAST PATH I302
J 0
(-7000 3875);
DISPLAY 1.021277 (-7000 3875);
DISPLAY INVISIBLE (-7000 3875);
FORCEADD OFFPAGE..2
R 2
(-6725 3425);
FORCEPROP 2 LAST $XR0 88 
J 0
(-6979 3425);
DISPLAY 0.638298 (-6979 3425);
PAINT MONO (-6979 3425);
FORCEPROP 2 LAST CDS_LIB standard
J 0
(-6725 3425);
DISPLAY INVISIBLE (-6725 3425);
FORCEPROP 1 LAST OFFPAGE TRUE
J 2
(-7050 3300);
DISPLAY 0.872340 (-7050 3300);
PAINT GREEN (-7050 3300);
DISPLAY INVISIBLE (-7050 3300);
FORCEPROP 1 LAST COMMENT_BODY TRUE
J 2
(-6680 3330);
DISPLAY 0.872340 (-6680 3330);
PAINT GREEN (-6680 3330);
DISPLAY INVISIBLE (-6680 3330);
FORCEPROP 2 LAST PATH I303
J 0
(-7000 3475);
DISPLAY 1.021277 (-7000 3475);
DISPLAY INVISIBLE (-7000 3475);
FORCEADD OFFPAGE..2
R 2
(-6725 2950);
FORCEPROP 2 LAST $XR0 88 
J 0
(-6979 2950);
DISPLAY 0.638298 (-6979 2950);
PAINT MONO (-6979 2950);
FORCEPROP 2 LAST CDS_LIB standard
J 0
(-6725 2950);
DISPLAY INVISIBLE (-6725 2950);
FORCEPROP 1 LAST OFFPAGE TRUE
J 2
(-7050 2825);
DISPLAY 0.872340 (-7050 2825);
PAINT GREEN (-7050 2825);
DISPLAY INVISIBLE (-7050 2825);
FORCEPROP 1 LAST COMMENT_BODY TRUE
J 2
(-6680 2855);
DISPLAY 0.872340 (-6680 2855);
PAINT GREEN (-6680 2855);
DISPLAY INVISIBLE (-6680 2855);
FORCEPROP 2 LAST PATH I304
J 0
(-7000 3000);
DISPLAY 1.021277 (-7000 3000);
DISPLAY INVISIBLE (-7000 3000);
FORCEADD OFFPAGE..2
R 2
(-6725 2900);
FORCEPROP 2 LAST $XR0 88 
J 0
(-6979 2900);
DISPLAY 0.638298 (-6979 2900);
PAINT MONO (-6979 2900);
FORCEPROP 2 LAST CDS_LIB standard
J 0
(-6725 2900);
DISPLAY INVISIBLE (-6725 2900);
FORCEPROP 1 LAST OFFPAGE TRUE
J 2
(-7050 2775);
DISPLAY 0.872340 (-7050 2775);
PAINT GREEN (-7050 2775);
DISPLAY INVISIBLE (-7050 2775);
FORCEPROP 1 LAST COMMENT_BODY TRUE
J 2
(-6680 2805);
DISPLAY 0.872340 (-6680 2805);
PAINT GREEN (-6680 2805);
DISPLAY INVISIBLE (-6680 2805);
FORCEPROP 2 LAST PATH I305
J 0
(-7000 2950);
DISPLAY 1.021277 (-7000 2950);
DISPLAY INVISIBLE (-7000 2950);
FORCEADD OFFPAGE..1
(-6725 2650);
FORCEPROP 2 LAST $XR0 88 
J 0
(-6946 2650);
DISPLAY 0.638298 (-6946 2650);
PAINT MONO (-6946 2650);
FORCEPROP 2 LAST CDS_LIB standard
J 0
(-6725 2650);
DISPLAY INVISIBLE (-6725 2650);
FORCEPROP 1 LAST OFFPAGE TRUE
J 0
(-6400 2525);
DISPLAY 0.872340 (-6400 2525);
PAINT GREEN (-6400 2525);
DISPLAY INVISIBLE (-6400 2525);
FORCEPROP 1 LAST COMMENT_BODY TRUE
J 0
(-6600 2550);
DISPLAY 0.872340 (-6600 2550);
PAINT GREEN (-6600 2550);
DISPLAY INVISIBLE (-6600 2550);
FORCEPROP 2 LAST PATH I306
J 0
(-6975 2700);
DISPLAY 1.021277 (-6975 2700);
DISPLAY INVISIBLE (-6975 2700);
FORCEADD OFFPAGE..2
R 2
(-6725 2800);
FORCEPROP 2 LAST $XR0 88 
J 0
(-6979 2800);
DISPLAY 0.638298 (-6979 2800);
PAINT MONO (-6979 2800);
FORCEPROP 2 LAST CDS_LIB standard
J 0
(-6725 2800);
DISPLAY INVISIBLE (-6725 2800);
FORCEPROP 1 LAST OFFPAGE TRUE
J 2
(-7050 2675);
DISPLAY 0.872340 (-7050 2675);
PAINT GREEN (-7050 2675);
DISPLAY INVISIBLE (-7050 2675);
FORCEPROP 1 LAST COMMENT_BODY TRUE
J 2
(-6680 2705);
DISPLAY 0.872340 (-6680 2705);
PAINT GREEN (-6680 2705);
DISPLAY INVISIBLE (-6680 2705);
FORCEPROP 2 LAST PATH I307
J 0
(-7000 2850);
DISPLAY 1.021277 (-7000 2850);
DISPLAY INVISIBLE (-7000 2850);
FORCEADD OFFPAGE..2
R 2
(-6725 2750);
FORCEPROP 2 LAST $XR0 88 
J 0
(-6979 2750);
DISPLAY 0.638298 (-6979 2750);
PAINT MONO (-6979 2750);
FORCEPROP 2 LAST CDS_LIB standard
J 0
(-6725 2750);
DISPLAY INVISIBLE (-6725 2750);
FORCEPROP 1 LAST OFFPAGE TRUE
J 2
(-7050 2625);
DISPLAY 0.872340 (-7050 2625);
PAINT GREEN (-7050 2625);
DISPLAY INVISIBLE (-7050 2625);
FORCEPROP 1 LAST COMMENT_BODY TRUE
J 2
(-6680 2655);
DISPLAY 0.872340 (-6680 2655);
PAINT GREEN (-6680 2655);
DISPLAY INVISIBLE (-6680 2655);
FORCEPROP 2 LAST PATH I308
J 0
(-7000 2800);
DISPLAY 1.021277 (-7000 2800);
DISPLAY INVISIBLE (-7000 2800);
FORCEADD OFFPAGE..5
(-6725 2550);
FORCEPROP 2 LAST $XR0 88 
J 0
(-6979 2550);
DISPLAY 0.638298 (-6979 2550);
PAINT MONO (-6979 2550);
FORCEPROP 2 LAST CDS_LIB mstr_standard
J 0
(-6725 2550);
DISPLAY INVISIBLE (-6725 2550);
FORCEPROP 1 LAST OFFPAGE TRUE
J 0
(-6400 2425);
DISPLAY 0.872340 (-6400 2425);
PAINT GREEN (-6400 2425);
DISPLAY INVISIBLE (-6400 2425);
FORCEPROP 1 LAST COMMENT_BODY TRUE
J 0
(-6625 2475);
DISPLAY 0.872340 (-6625 2475);
PAINT GREEN (-6625 2475);
DISPLAY INVISIBLE (-6625 2475);
FORCEPROP 2 LAST PATH I309
J 0
(-7000 2600);
DISPLAY 1.021277 (-7000 2600);
DISPLAY INVISIBLE (-7000 2600);
FORCEADD OFFPAGE..2
R 2
(-6725 2450);
FORCEPROP 2 LAST $XR0 88 
J 0
(-6979 2450);
DISPLAY 0.638298 (-6979 2450);
PAINT MONO (-6979 2450);
FORCEPROP 2 LAST CDS_LIB standard
J 0
(-6725 2450);
DISPLAY INVISIBLE (-6725 2450);
FORCEPROP 1 LAST OFFPAGE TRUE
J 2
(-7050 2325);
DISPLAY 0.872340 (-7050 2325);
PAINT GREEN (-7050 2325);
DISPLAY INVISIBLE (-7050 2325);
FORCEPROP 1 LAST COMMENT_BODY TRUE
J 2
(-6680 2355);
DISPLAY 0.872340 (-6680 2355);
PAINT GREEN (-6680 2355);
DISPLAY INVISIBLE (-6680 2355);
FORCEPROP 2 LAST PATH I310
J 0
(-7000 2500);
DISPLAY 1.021277 (-7000 2500);
DISPLAY INVISIBLE (-7000 2500);
FORCEADD OFFPAGE..2
R 2
(-6725 2400);
FORCEPROP 2 LAST $XR0 88 
J 0
(-6979 2400);
DISPLAY 0.638298 (-6979 2400);
PAINT MONO (-6979 2400);
FORCEPROP 2 LAST CDS_LIB standard
J 0
(-6725 2400);
DISPLAY INVISIBLE (-6725 2400);
FORCEPROP 1 LAST OFFPAGE TRUE
J 2
(-7050 2275);
DISPLAY 0.872340 (-7050 2275);
PAINT GREEN (-7050 2275);
DISPLAY INVISIBLE (-7050 2275);
FORCEPROP 1 LAST COMMENT_BODY TRUE
J 2
(-6680 2305);
DISPLAY 0.872340 (-6680 2305);
PAINT GREEN (-6680 2305);
DISPLAY INVISIBLE (-6680 2305);
FORCEPROP 2 LAST PATH I311
J 0
(-7000 2450);
DISPLAY 1.021277 (-7000 2450);
DISPLAY INVISIBLE (-7000 2450);
FORCEADD OFFPAGE..1
(-6725 2300);
FORCEPROP 2 LAST $XR0 88 
J 0
(-6946 2300);
DISPLAY 0.638298 (-6946 2300);
PAINT MONO (-6946 2300);
FORCEPROP 2 LAST CDS_LIB standard
J 0
(-6725 2300);
DISPLAY INVISIBLE (-6725 2300);
FORCEPROP 1 LAST OFFPAGE TRUE
J 0
(-6400 2175);
DISPLAY 0.872340 (-6400 2175);
PAINT GREEN (-6400 2175);
DISPLAY INVISIBLE (-6400 2175);
FORCEPROP 1 LAST COMMENT_BODY TRUE
J 0
(-6600 2200);
DISPLAY 0.872340 (-6600 2200);
PAINT GREEN (-6600 2200);
DISPLAY INVISIBLE (-6600 2200);
FORCEPROP 2 LAST PATH I312
J 0
(-6975 2350);
DISPLAY 1.021277 (-6975 2350);
DISPLAY INVISIBLE (-6975 2350);
FORCEADD OFFPAGE..5
(-6725 2200);
FORCEPROP 2 LAST $XR0 88 
J 0
(-6979 2200);
DISPLAY 0.638298 (-6979 2200);
PAINT MONO (-6979 2200);
FORCEPROP 2 LAST CDS_LIB standard
J 0
(-6725 2200);
DISPLAY INVISIBLE (-6725 2200);
FORCEPROP 1 LAST OFFPAGE TRUE
J 0
(-6400 2075);
DISPLAY 0.872340 (-6400 2075);
PAINT GREEN (-6400 2075);
DISPLAY INVISIBLE (-6400 2075);
FORCEPROP 1 LAST COMMENT_BODY TRUE
J 0
(-6625 2125);
DISPLAY 0.872340 (-6625 2125);
PAINT GREEN (-6625 2125);
DISPLAY INVISIBLE (-6625 2125);
FORCEPROP 2 LAST PATH I313
J 0
(-7000 2250);
DISPLAY 1.021277 (-7000 2250);
DISPLAY INVISIBLE (-7000 2250);
FORCEADD Q_RES..1
(-7050 2100);
FORCEPROP 1 LAST LOCATION R377
J 0
(-7375 2100);
DISPLAY 0.489362 (-7375 2100);
PAINT SKYBLUE (-7375 2100);
FORCEPROP 0 LAST $SEC 1
J 0
(-7225 2150);
DISPLAY 0.680851 (-7225 2150);
PAINT MONO (-7225 2150);
DISPLAY INVISIBLE (-7225 2150);
FORCEPROP 0 LAST CDS_SEC 1
J 0
(-7225 2150);
DISPLAY 1.021277 (-7225 2150);
DISPLAY INVISIBLE (-7225 2150);
FORCEPROP 1 LASTPIN (-7150 2100) $PN 1
J 0
(-7138 2112);
DISPLAY 0.489362 (-7138 2112);
PAINT MONO (-7138 2112);
FORCEPROP 1 LASTPIN (-6950 2100) $PN 2
J 0
(-6988 2112);
DISPLAY 0.489362 (-6988 2112);
PAINT MONO (-6988 2112);
FORCEPROP 1 LAST PACK_TYPE 0402LF
J 0
(-7375 2075);
DISPLAY 0.489362 (-7375 2075);
PAINT SKYBLUE (-7375 2075);
FORCEPROP 1 LAST TOLERANCE 1%
J 0
(-6775 2100);
DISPLAY 0.489362 (-6775 2100);
PAINT SKYBLUE (-6775 2100);
FORCEPROP 1 LAST VALUE 15
J 2
(-6725 2100);
DISPLAY 0.489362 (-6725 2100);
PAINT SKYBLUE (-6725 2100);
FORCEPROP 1 LAST MATERIAL CHIP
J 0
(-7175 2225);
DISPLAY 0.638298 (-7175 2225);
PAINT SKYBLUE (-7175 2225);
DISPLAY INVISIBLE (-7175 2225);
FORCEPROP 1 LAST WATTAGE 1/16W
J 2
(-6825 2225);
DISPLAY 0.638298 (-6825 2225);
PAINT SKYBLUE (-6825 2225);
DISPLAY INVISIBLE (-6825 2225);
FORCEPROP 2 LAST CDS_LIB pure_quanta
J 0
(-7050 2100);
DISPLAY INVISIBLE (-7050 2100);
FORCEPROP 1 LAST PATH I314
J 0
(-7100 2250);
DISPLAY 0.978723 (-7100 2250);
PAINT WHITE (-7100 2250);
DISPLAY INVISIBLE (-7100 2250);
FORCEPROP 1 LAST PART_NUMBER CS01502FB03
J 0
(-6925 2075);
DISPLAY 0.489362 (-6925 2075);
PAINT SKYBLUE (-6925 2075);
DISPLAY INVISIBLE (-6925 2075);
FORCEADD OFFPAGE..1
(-7925 2100);
FORCEPROP 2 LAST $XR0 88 
J 0
(-8176 2100);
DISPLAY 0.638298 (-8176 2100);
PAINT MONO (-8176 2100);
FORCEPROP 2 LAST CDS_LIB mstr_standard
J 0
(-7925 2100);
DISPLAY INVISIBLE (-7925 2100);
FORCEPROP 1 LAST OFFPAGE TRUE
J 0
(-7600 1975);
DISPLAY 0.872340 (-7600 1975);
PAINT GREEN (-7600 1975);
DISPLAY INVISIBLE (-7600 1975);
FORCEPROP 1 LAST COMMENT_BODY TRUE
J 0
(-7800 2000);
DISPLAY 0.872340 (-7800 2000);
PAINT GREEN (-7800 2000);
DISPLAY INVISIBLE (-7800 2000);
FORCEPROP 2 LAST PATH I315
J 0
(-8200 2150);
DISPLAY 1.021277 (-8200 2150);
DISPLAY INVISIBLE (-8200 2150);
FORCEADD OFFPAGE..5
(-6725 2000);
FORCEPROP 2 LAST $XR0 88 
J 0
(-6979 2000);
DISPLAY 0.638298 (-6979 2000);
PAINT MONO (-6979 2000);
FORCEPROP 2 LAST CDS_LIB standard
J 0
(-6725 2000);
DISPLAY INVISIBLE (-6725 2000);
FORCEPROP 1 LAST OFFPAGE TRUE
J 0
(-6400 1875);
DISPLAY 0.872340 (-6400 1875);
PAINT GREEN (-6400 1875);
DISPLAY INVISIBLE (-6400 1875);
FORCEPROP 1 LAST COMMENT_BODY TRUE
J 0
(-6625 1925);
DISPLAY 0.872340 (-6625 1925);
PAINT GREEN (-6625 1925);
DISPLAY INVISIBLE (-6625 1925);
FORCEPROP 2 LAST PATH I316
J 0
(-7000 2050);
DISPLAY 1.021277 (-7000 2050);
DISPLAY INVISIBLE (-7000 2050);
FORCEADD QUANTA_TITLE_BLOCK_C..1
(-100 100);
FORCEPROP 0 LAST CDS_CON_LAST_MODIFIED Thu Sep 14 16:11:49 2023
J 0
(-1985 115);
DISPLAY INVISIBLE (-1985 115);
FORCEPROP 1 LAST CUSTOM_TXT_CDS <CON_LAST_MODIFIED>
J 0
(-1985 115);
DISPLAY 0.978723 (-1985 115);
FORCEPROP 2 LAST CUSTOM_TXT_CDS <XR_PAGE_TITLE>
J 0
(-7990 5350);
DISPLAY 0.638298 (-7990 5350);
PAINT PINK (-7990 5350);
DISPLAY INVISIBLE (-7990 5350);
FORCEPROP 1 LAST CUSTOM_TXT_CDS <NAME_2>
J 0
(-3275 150);
FORCEPROP 1 LAST CUSTOM_TXT_CDS <NAME_1>
J 0
(-3275 275);
FORCEPROP 1 LAST CUSTOM_TXT_CDS <Q_NUMBER>
J 0
(-1503 203);
DISPLAY 1.212766 (-1503 203);
FORCEPROP 1 LAST CUSTOM_TXT_CDS <Q_PROJ>
J 0
(-2482 202);
DISPLAY 1.212766 (-2482 202);
FORCEPROP 1 LAST CUSTOM_TXT_CDS <Q_REV>
J 0
(-284 203);
DISPLAY 1.212766 (-284 203);
FORCEPROP 1 LAST CUSTOM_TXT_CDS <CON_PAGE_NUM> OF <CON_TOTAL_PAGES>
J 0
(-546 118);
DISPLAY 0.978723 (-546 118);
FORCEPROP 1 LAST Q_TITLE CPU0 DDR CHC
J 0
(-9400 150);
DISPLAY 2.446809 (-9400 150);
PAINT GREEN (-9400 150);
FORCEPROP 1 LAST CDS_LMAN_SYM_OUTLINE -9475,6775,100,-125
J 0
(-100 100);
DISPLAY 0.468085 (-100 100);
PAINT GREEN (-100 100);
DISPLAY INVISIBLE (-100 100);
FORCEPROP 2 LAST CDS_LIB pure_quanta
J 0
(-100 100);
DISPLAY INVISIBLE (-100 100);
FORCEPROP 2 LAST PAGE_BORDER TRUE
J 0
(-7990 5350);
DISPLAY 0.638298 (-7990 5350);
PAINT PINK (-7990 5350);
DISPLAY INVISIBLE (-7990 5350);
FORCEPROP 2 LAST CDS_XR_PAGE_TITLE CR-12 : @T6G_MB_LIB.T6G(SCH_1):PAGE12
J 0
(-7990 5350);
DISPLAY 0.638298 (-7990 5350);
PAINT PINK (-7990 5350);
DISPLAY INVISIBLE (-7990 5350);
FORCEPROP 1 LAST Q_DEPT BU9
J 1
(-3863 149);
DISPLAY 1.957447 (-3863 149);
PAINT GREEN (-3863 149);
DISPLAY INVISIBLE (-3863 149);
FORCEPROP 1 LAST COMMENT_BODY TRUE
J 0
(-88 87);
DISPLAY 0.978723 (-88 87);
PAINT GREEN (-88 87);
DISPLAY INVISIBLE (-88 87);
FORCEADD CAD_NOTE..1
(-7825 2375);
FORCEPROP 0 LAST L1 R1951 PLACE CLOSE TO CPU < 25MM
J 0
(-7975 2250);
DISPLAY 0.617021 (-7975 2250);
PAINT WHITE (-7975 2250);
FORCEPROP 2 LAST CDS_LIB pure_quanta_power
J 0
(-7825 2375);
DISPLAY INVISIBLE (-7825 2375);
FORCEPROP 1 LAST COMMENT_BODY TRUE
J 0
(-7800 2475);
DISPLAY 0.574468 (-7800 2475);
PAINT WHITE (-7800 2475);
DISPLAY INVISIBLE (-7800 2475);
WIRE 17 -1 (-3450 5275)(-3450 5225);
WIRE 17 -1 (-3450 5325)(-3450 5275);
WIRE 17 -1 (-3450 5225)(-3450 5175);
WIRE 17 -1 (-3450 5075)(-3450 5175);
WIRE 17 -1 (-3450 5375)(-3450 5325);
WIRE 17 -1 (-3450 5425)(-3450 5375);
WIRE 17 -1 (-3450 5025)(-3450 5075);
WIRE 17 -1 (-3450 4975)(-3450 5025);
WIRE 17 -1 (-3450 5475)(-3450 5425);
WIRE 17 -1 (-3450 5525)(-3450 5475);
WIRE 17 -1 (-3450 4925)(-3450 4975);
WIRE 17 -1 (-3450 4925)(-3450 4875);
WIRE 17 -1 (-3450 5625)(-3450 5525);
WIRE 17 -1 (-3450 5675)(-3450 5625);
WIRE 17 -1 (-3450 4875)(-3450 4825);
WIRE 17 -1 (-3450 4825)(-3450 4775);
WIRE 17 -1 (-3450 5725)(-3450 5675);
WIRE 17 -1 (-3450 5775)(-3450 5725);
WIRE 17 -1 (-3450 4775)(-3450 4725);
WIRE 17 -1 (-3450 4725)(-3450 4625);
WIRE 17 -1 (-3450 5825)(-3450 5775);
WIRE 17 -1 (-3450 5875)(-3450 5825);
WIRE 17 -1 (-3450 4625)(-3450 4575);
WIRE 17 -1 (-3450 4575)(-3450 4525);
WIRE 17 -1 (-3450 5925)(-3450 5875);
WIRE 17 -1 (-3450 5975)(-3450 5925);
WIRE 17 -1 (-3450 4525)(-3450 4475);
WIRE 17 -1 (-3450 4425)(-3450 4475);
WIRE 17 -1 (-3450 5975)(-2825 5975);
FORCEPROP 2 LAST SIG_NAME M_C_CPU0_SA_DQ<31:0>
J 2
(-2885 5985);
DISPLAY 0.489362 (-2885 5985);
WIRE 17 -1 (-3450 4375)(-3450 4425);
WIRE 17 -1 (-3450 4325)(-3450 4375);
WIRE 17 -1 (-3450 4275)(-3450 4325);
WIRE 17 -1 (-3450 4175)(-2825 4175);
FORCEPROP 2 LAST SIG_NAME M_C_CPU0_SB_DQ<31:0>
J 2
(-2885 4185);
DISPLAY 0.489362 (-2885 4185);
WIRE 17 -1 (-3450 4175)(-3450 4125);
WIRE 17 -1 (-3450 3825)(-3450 3725);
WIRE 17 -1 (-3450 3875)(-3450 3825);
WIRE 17 -1 (-3450 3725)(-3450 3675);
WIRE 17 -1 (-3450 3675)(-3450 3625);
WIRE 17 -1 (-3450 3925)(-3450 3875);
WIRE 17 -1 (-3450 3975)(-3450 3925);
WIRE 17 -1 (-3450 3625)(-3450 3575);
WIRE 17 -1 (-3450 3575)(-3450 3525);
WIRE 17 -1 (-3450 4025)(-3450 3975);
WIRE 17 -1 (-3450 4075)(-3450 4025);
WIRE 17 -1 (-3450 3525)(-3450 3475);
WIRE 17 -1 (-3450 3475)(-3450 3425);
WIRE 17 -1 (-3450 4125)(-3450 4075);
WIRE 17 -1 (-3450 3425)(-3450 3375);
WIRE 17 -1 (-3450 3275)(-3450 3375);
WIRE 17 -1 (-3450 3225)(-3450 3275);
WIRE 17 -1 (-3450 3175)(-3450 3225);
WIRE 17 -1 (-3450 3125)(-3450 3175);
WIRE 17 -1 (-3450 3125)(-3450 3075);
WIRE 17 -1 (-3450 3075)(-3450 3025);
WIRE 17 -1 (-3450 3025)(-3450 2975);
WIRE 17 -1 (-3450 2975)(-3450 2925);
WIRE 17 -1 (-3450 2925)(-3450 2825);
WIRE 17 -1 (-3450 2825)(-3450 2775);
WIRE 17 -1 (-3450 2775)(-3450 2725);
WIRE 17 -1 (-3450 2725)(-3450 2675);
WIRE 17 -1 (-3450 2625)(-3450 2675);
WIRE 17 -1 (-3450 2575)(-3450 2625);
WIRE 17 -1 (-3450 2525)(-3450 2575);
WIRE 17 -1 (-3450 2475)(-3450 2525);
WIRE 17 -1 (-3450 2075)(-3450 2125);
WIRE 17 -1 (-3450 2025)(-3450 2075);
WIRE 17 -1 (-3450 2125)(-3450 2175);
WIRE 17 -1 (-3450 2175)(-3450 2225);
WIRE 17 -1 (-3450 2275)(-3450 2225);
WIRE 17 -1 (-3450 2275)(-3450 2325);
WIRE 17 -1 (-3450 2375)(-3450 2325);
WIRE 17 -1 (-3450 2375)(-3450 2400);
WIRE 17 -1 (-3450 2400)(-2950 2400);
FORCEPROP 2 LAST SIG_NAME M_C_CPU0_SA_CB<7:0>
J 2
(-2950 2410);
DISPLAY 0.489362 (-2950 2410);
WIRE 17 -1 (-3450 1925)(-3450 1950);
WIRE 17 -1 (-3450 1925)(-3450 1875);
WIRE 17 -1 (-3450 1950)(-2950 1950);
FORCEPROP 2 LAST SIG_NAME M_C_CPU0_SB_CB<7:0>
J 2
(-2950 1960);
DISPLAY 0.489362 (-2950 1960);
WIRE 17 -1 (-3450 1825)(-3450 1875);
WIRE 17 -1 (-3450 1825)(-3450 1775);
WIRE 17 -1 (-3450 1725)(-3450 1775);
WIRE 17 -1 (-3450 1675)(-3450 1725);
WIRE 17 -1 (-3450 1625)(-3450 1675);
WIRE 17 -1 (-3450 1575)(-3450 1625);
WIRE 17 -1 (-6175 5925)(-6175 5825);
FORCEPROP 2 LAST SIG_NAME M_C_CPU0_SA_DQS_DN<9:0>
J 2
(-6210 5935);
DISPLAY 0.489362 (-6210 5935);
WIRE 17 -1 (-6175 5825)(-6175 5725);
WIRE 17 -1 (-6175 5725)(-6175 5625);
WIRE 17 -1 (-6175 5625)(-6175 5525);
WIRE 17 -1 (-6175 5425)(-6175 5525);
WIRE 17 -1 (-6175 5325)(-6175 5425);
WIRE 17 -1 (-5975 5975)(-5975 5875);
WIRE 17 -1 (-5975 5975)(-6775 5975);
FORCEPROP 2 LAST SIG_NAME M_C_CPU0_SA_DQS_DP<9:0>
J 2
(-6210 5985);
DISPLAY 0.489362 (-6210 5985);
WIRE 17 -1 (-6175 5225)(-6175 5325);
WIRE 17 -1 (-6175 5225)(-6175 5125);
WIRE 17 -1 (-6175 5125)(-6175 5025);
WIRE 17 -1 (-5975 5875)(-5975 5775);
WIRE 17 -1 (-5975 5775)(-5975 5675);
WIRE 17 -1 (-5975 5675)(-5975 5575);
WIRE 17 -1 (-5975 5475)(-5975 5575);
WIRE 17 -1 (-5975 5375)(-5975 5475);
WIRE 17 -1 (-5975 5275)(-5975 5375);
WIRE 17 -1 (-5975 5275)(-5975 5175);
WIRE 17 -1 (-5975 5175)(-5975 5075);
WIRE 17 -1 (-5975 4225)(-5975 4125);
WIRE 17 -1 (-5975 4225)(-5975 4325);
WIRE 17 -1 (-5975 4125)(-5975 4025);
WIRE 17 -1 (-5975 4325)(-5975 4425);
WIRE 17 -1 (-5975 4425)(-5975 4525);
WIRE 17 -1 (-5975 4625)(-5975 4525);
WIRE 17 -1 (-5975 4725)(-5975 4625);
WIRE 17 -1 (-5975 4825)(-5975 4725);
WIRE 17 -1 (-5975 4925)(-5975 4825);
WIRE 17 -1 (-5975 4925)(-6775 4925);
FORCEPROP 2 LAST SIG_NAME M_C_CPU0_SB_DQS_DP<9:0>
J 2
(-6210 4935);
DISPLAY 0.489362 (-6210 4935);
WIRE 17 -1 (-6175 4875)(-6175 4775);
FORCEPROP 2 LAST SIG_NAME M_C_CPU0_SB_DQS_DN<9:0>
J 2
(-6210 4885);
DISPLAY 0.489362 (-6210 4885);
WIRE 17 -1 (-6175 4775)(-6175 4675);
WIRE 17 -1 (-6175 4675)(-6175 4575);
WIRE 17 -1 (-6175 4575)(-6175 4475);
WIRE 17 -1 (-6175 4375)(-6175 4475);
WIRE 17 -1 (-6175 4275)(-6175 4375);
WIRE 17 -1 (-6175 4175)(-6175 4275);
WIRE 17 -1 (-6175 4175)(-6175 4075);
WIRE 17 -1 (-6175 4075)(-6175 3975);
WIRE 17 -1 (-6175 3775)(-6175 3825);
WIRE 17 -1 (-6175 3725)(-6175 3775);
WIRE 17 -1 (-6175 3825)(-6675 3825);
FORCEPROP 2 LAST SIG_NAME M_C_CPU0_SA_CA<6:0>
J 0
(-6675 3835);
DISPLAY 0.489362 (-6675 3835);
WIRE 17 -1 (-6175 3375)(-6175 3425);
WIRE 17 -1 (-6175 3325)(-6175 3375);
WIRE 17 -1 (-6175 3425)(-6675 3425);
FORCEPROP 2 LAST SIG_NAME M_C_CPU0_SB_CA<6:0>
J 0
(-6675 3435);
DISPLAY 0.489362 (-6675 3435);
WIRE 17 -1 (-6175 3675)(-6175 3725);
WIRE 17 -1 (-6175 3275)(-6175 3325);
WIRE 17 -1 (-6175 3625)(-6175 3675);
WIRE 17 -1 (-6175 3575)(-6175 3625);
WIRE 17 -1 (-6175 3525)(-6175 3575);
WIRE 17 -1 (-6175 3225)(-6175 3275);
WIRE 17 -1 (-6175 3175)(-6175 3225);
WIRE 17 -1 (-6175 3125)(-6175 3175);
WIRE 17 -1 (-6175 5925)(-6775 5925);
WIRE 17 -1 (-6175 4875)(-6775 4875);
WIRE 16 -1 (-7875 2100)(-7150 2100);
FORCEPROP 2 LAST SIG_NAME M_C_CPU0_ALERT_N
J 0
(-7835 2110);
DISPLAY 0.489362 (-7835 2110);
WIRE 16 -1 (-6950 2100)(-5575 2100);
FORCEPROP 2 LAST SIG_NAME M_C_CPU0_ALERT_R_N
J 0
(-6660 2110);
DISPLAY 0.489362 (-6660 2110);
FORCEPROP 2 LASTPROP $XRERR UNIQUE?
J 0
(-6900 2110);
DISPLAY 0.638298 (-6900 2110);
PAINT MONO (-6900 2110);
DISPLAY INVISIBLE (-6900 2110);
WIRE 16 -1 (-6675 1150)(-5575 1150);
FORCEPROP 2 LAST SIG_NAME TP_M_C_CPU0_SA_TEST39C
J 0
(-6660 1160);
DISPLAY 0.489362 (-6660 1160);
FORCEPROP 2 LASTPROP $XRERR UNIQUE?
J 0
(-6915 1150);
DISPLAY 0.638298 (-6915 1150);
PAINT MONO (-6915 1150);
DISPLAY INVISIBLE (-6915 1150);
WIRE 16 -1 (-6675 2950)(-5575 2950);
FORCEPROP 2 LAST SIG_NAME M_C_CPU0_CLK_DP<0>
J 0
(-6675 2960);
DISPLAY 0.489362 (-6675 2960);
WIRE 16 -1 (-6675 2900)(-5575 2900);
FORCEPROP 2 LAST SIG_NAME M_C_CPU0_CLK_DN<0>
J 0
(-6675 2910);
DISPLAY 0.489362 (-6675 2910);
WIRE 16 -1 (-6675 2650)(-5575 2650);
FORCEPROP 2 LAST SIG_NAME M_C_CPU0_SA_RSP<0>
J 0
(-6675 2660);
DISPLAY 0.489362 (-6675 2660);
WIRE 16 -1 (-6675 2800)(-5575 2800);
FORCEPROP 2 LAST SIG_NAME M_C_CPU0_SA_CS_N<0>
J 0
(-6675 2810);
DISPLAY 0.489362 (-6675 2810);
WIRE 16 -1 (-6675 2750)(-5575 2750);
FORCEPROP 2 LAST SIG_NAME M_C_CPU0_SA_CS_N<1>
J 0
(-6675 2760);
DISPLAY 0.489362 (-6675 2760);
WIRE 16 -1 (-6675 2550)(-5575 2550);
FORCEPROP 2 LAST SIG_NAME M_C_CPU0_SA_PAR
J 0
(-6675 2560);
DISPLAY 0.489362 (-6675 2560);
WIRE 16 -1 (-6675 2450)(-5575 2450);
FORCEPROP 2 LAST SIG_NAME M_C_CPU0_SB_CS_N<0>
J 0
(-6675 2460);
DISPLAY 0.489362 (-6675 2460);
WIRE 16 -1 (-6675 2400)(-5575 2400);
FORCEPROP 2 LAST SIG_NAME M_C_CPU0_SB_CS_N<1>
J 0
(-6675 2410);
DISPLAY 0.489362 (-6675 2410);
WIRE 16 -1 (-6675 2300)(-5575 2300);
FORCEPROP 2 LAST SIG_NAME M_C_CPU0_SB_RSP<0>
J 0
(-6675 2310);
DISPLAY 0.489362 (-6675 2310);
WIRE 16 -1 (-6675 2200)(-5575 2200);
FORCEPROP 2 LAST SIG_NAME M_C_CPU0_SB_PAR
J 0
(-6675 2210);
DISPLAY 0.489362 (-6675 2210);
WIRE 16 -1 (-6675 2000)(-5575 2000);
FORCEPROP 2 LAST SIG_NAME M_C_CPU0_RESET_N
J 0
(-6675 2010);
DISPLAY 0.489362 (-6675 2010);
WIRE 16 -1 (-5875 4000)(-5575 4000);
WIRE 16 -1 (-6075 3100)(-5575 3100);
WIRE 16 -1 (-6075 3950)(-5575 3950);
WIRE 16 -1 (-6075 3500)(-5575 3500);
WIRE 16 -1 (-6075 3150)(-5575 3150);
WIRE 16 -1 (-6075 4050)(-5575 4050);
WIRE 16 -1 (-6075 3550)(-5575 3550);
WIRE 16 -1 (-6075 3200)(-5575 3200);
WIRE 16 -1 (-6075 3600)(-5575 3600);
WIRE 16 -1 (-6075 3250)(-5575 3250);
WIRE 16 -1 (-6075 3650)(-5575 3650);
WIRE 16 -1 (-6075 3300)(-5575 3300);
WIRE 16 -1 (-6075 3700)(-5575 3700);
WIRE 16 -1 (-6075 3350)(-5575 3350);
WIRE 16 -1 (-6075 3750)(-5575 3750);
WIRE 16 -1 (-6075 3400)(-5575 3400);
WIRE 16 -1 (-6075 3800)(-5575 3800);
WIRE 16 -1 (-5875 4200)(-5575 4200);
WIRE 16 -1 (-5875 4300)(-5575 4300);
WIRE 16 -1 (-5875 4400)(-5575 4400);
WIRE 16 -1 (-5875 4500)(-5575 4500);
WIRE 16 -1 (-5875 5050)(-5575 5050);
WIRE 16 -1 (-5875 4600)(-5575 4600);
WIRE 16 -1 (-6075 4150)(-5575 4150);
WIRE 16 -1 (-5875 4700)(-5575 4700);
WIRE 16 -1 (-6075 4250)(-5575 4250);
WIRE 16 -1 (-5875 4800)(-5575 4800);
WIRE 16 -1 (-6075 4350)(-5575 4350);
WIRE 16 -1 (-5875 4900)(-5575 4900);
WIRE 16 -1 (-6075 4450)(-5575 4450);
WIRE 16 -1 (-6075 5000)(-5575 5000);
WIRE 16 -1 (-6075 4550)(-5575 4550);
WIRE 16 -1 (-6075 5100)(-5575 5100);
WIRE 16 -1 (-6075 4650)(-5575 4650);
WIRE 16 -1 (-6075 4750)(-5575 4750);
WIRE 16 -1 (-6075 4850)(-5575 4850);
WIRE 16 -1 (-5875 4100)(-5575 4100);
WIRE 16 -1 (-6075 5900)(-5575 5900);
WIRE 16 -1 (-5875 5150)(-5575 5150);
WIRE 16 -1 (-5875 5250)(-5575 5250);
WIRE 16 -1 (-5875 5350)(-5575 5350);
WIRE 16 -1 (-5875 5450)(-5575 5450);
WIRE 16 -1 (-5875 5550)(-5575 5550);
WIRE 16 -1 (-5875 5650)(-5575 5650);
WIRE 16 -1 (-6075 5200)(-5575 5200);
WIRE 16 -1 (-5875 5750)(-5575 5750);
WIRE 16 -1 (-6075 5300)(-5575 5300);
WIRE 16 -1 (-5875 5850)(-5575 5850);
WIRE 16 -1 (-6075 5400)(-5575 5400);
WIRE 16 -1 (-5875 5950)(-5575 5950);
WIRE 16 -1 (-6075 5500)(-5575 5500);
WIRE 16 -1 (-6075 5600)(-5575 5600);
WIRE 16 -1 (-6075 5700)(-5575 5700);
WIRE 16 -1 (-6075 5800)(-5575 5800);
WIRE 16 -1 (-3975 1550)(-3550 1550);
WIRE 16 -1 (-3975 1600)(-3550 1600);
WIRE 16 -1 (-3975 1650)(-3550 1650);
WIRE 16 -1 (-3975 1700)(-3550 1700);
WIRE 16 -1 (-3975 1750)(-3550 1750);
WIRE 16 -1 (-3975 1800)(-3550 1800);
WIRE 16 -1 (-3975 2000)(-3550 2000);
WIRE 16 -1 (-3975 1850)(-3550 1850);
WIRE 16 -1 (-3975 1900)(-3550 1900);
WIRE 16 -1 (-3975 2150)(-3550 2150);
WIRE 16 -1 (-3975 2200)(-3550 2200);
WIRE 16 -1 (-3975 2250)(-3550 2250);
WIRE 16 -1 (-3975 2300)(-3550 2300);
WIRE 16 -1 (-3975 2350)(-3550 2350);
WIRE 16 -1 (-3975 2550)(-3550 2550);
WIRE 16 -1 (-3975 2600)(-3550 2600);
WIRE 16 -1 (-3975 2650)(-3550 2650);
WIRE 16 -1 (-3975 2700)(-3550 2700);
WIRE 16 -1 (-3975 2750)(-3550 2750);
WIRE 16 -1 (-3975 2800)(-3550 2800);
WIRE 16 -1 (-3975 2900)(-3550 2900);
WIRE 16 -1 (-3975 2950)(-3550 2950);
WIRE 16 -1 (-3975 3000)(-3550 3000);
WIRE 16 -1 (-3975 2050)(-3550 2050);
WIRE 16 -1 (-3975 3050)(-3550 3050);
WIRE 16 -1 (-3975 2450)(-3550 2450);
WIRE 16 -1 (-3975 2100)(-3550 2100);
WIRE 16 -1 (-3975 2500)(-3550 2500);
WIRE 16 -1 (-3975 3800)(-3550 3800);
WIRE 16 -1 (-3975 3850)(-3550 3850);
WIRE 16 -1 (-3975 3900)(-3550 3900);
WIRE 16 -1 (-3975 3950)(-3550 3950);
WIRE 16 -1 (-3975 4000)(-3550 4000);
WIRE 16 -1 (-3975 4050)(-3550 4050);
WIRE 16 -1 (-3975 3100)(-3550 3100);
WIRE 16 -1 (-3975 3150)(-3550 3150);
WIRE 16 -1 (-3975 3200)(-3550 3200);
WIRE 16 -1 (-3975 3250)(-3550 3250);
WIRE 16 -1 (-3975 3350)(-3550 3350);
WIRE 16 -1 (-3975 3400)(-3550 3400);
WIRE 16 -1 (-3975 3450)(-3550 3450);
WIRE 16 -1 (-3975 3500)(-3550 3500);
WIRE 16 -1 (-3975 3550)(-3550 3550);
WIRE 16 -1 (-3975 3600)(-3550 3600);
WIRE 16 -1 (-3975 3650)(-3550 3650);
WIRE 16 -1 (-3975 3700)(-3550 3700);
WIRE 16 -1 (-3975 4600)(-3550 4600);
WIRE 16 -1 (-3975 4700)(-3550 4700);
WIRE 16 -1 (-3975 4750)(-3550 4750);
WIRE 16 -1 (-3975 4800)(-3550 4800);
WIRE 16 -1 (-3975 4850)(-3550 4850);
WIRE 16 -1 (-3975 4250)(-3550 4250);
WIRE 16 -1 (-3975 4300)(-3550 4300);
WIRE 16 -1 (-3975 4100)(-3550 4100);
WIRE 16 -1 (-3975 4150)(-3550 4150);
WIRE 16 -1 (-3975 4900)(-3550 4900);
WIRE 16 -1 (-3975 4950)(-3550 4950);
WIRE 16 -1 (-3975 4350)(-3550 4350);
WIRE 16 -1 (-3975 5000)(-3550 5000);
WIRE 16 -1 (-3975 4400)(-3550 4400);
WIRE 16 -1 (-3975 5050)(-3550 5050);
WIRE 16 -1 (-3975 4450)(-3550 4450);
WIRE 16 -1 (-3975 4500)(-3550 4500);
WIRE 16 -1 (-3975 4550)(-3550 4550);
WIRE 16 -1 (-3975 5500)(-3550 5500);
WIRE 16 -1 (-3975 5250)(-3550 5250);
WIRE 16 -1 (-3975 5600)(-3550 5600);
WIRE 16 -1 (-3975 5300)(-3550 5300);
WIRE 16 -1 (-3975 5650)(-3550 5650);
WIRE 16 -1 (-3975 5350)(-3550 5350);
WIRE 16 -1 (-3975 5700)(-3550 5700);
WIRE 16 -1 (-3975 5400)(-3550 5400);
WIRE 16 -1 (-3975 5750)(-3550 5750);
WIRE 16 -1 (-3975 5800)(-3550 5800);
WIRE 16 -1 (-3975 5850)(-3550 5850);
WIRE 16 -1 (-3975 5900)(-3550 5900);
WIRE 16 -1 (-3975 5950)(-3550 5950);
WIRE 16 -1 (-3975 5150)(-3550 5150);
WIRE 16 -1 (-3975 5450)(-3550 5450);
WIRE 16 -1 (-3975 5200)(-3550 5200);
QUIT
